FILE_TYPE = MACRO_DRAWING;
SET COLOR_WIRE YELLOW;
SET COLOR_PROP MONO;
SET COLOR_DOT WHITE;
SET COLOR_ARC YELLOW;
SET COLOR_BODY GREEN;
SET COLOR_NOTE MONO;
SET PROP_DISPLAY VALUE;
SET PAGE_NUMBER P169;
FORCEADD OFFPAGE..2
(1225 2900);
FORCEPROP 2 LAST $XR0 147 
J 0
(1414 2900);
DISPLAY 0.638298 (1414 2900);
PAINT MONO (1414 2900);
FORCEPROP 2 LAST $XR1 165 
J 0
(1534 2900);
DISPLAY 0.638298 (1534 2900);
PAINT MONO (1534 2900);
FORCEPROP 2 LAST CDS_LIB mstr_standard
J 0
(1225 2900);
DISPLAY 1.361702 (1225 2900);
PAINT ORANGE (1225 2900);
DISPLAY INVISIBLE (1225 2900);
FORCEPROP 1 LAST OFFPAGE TRUE
J 0
(1550 2775);
PAINT GREEN (1550 2775);
DISPLAY INVISIBLE (1550 2775);
FORCEPROP 1 LAST COMMENT_BODY TRUE
J 0
(1180 2805);
DISPLAY 1.170213 (1180 2805);
PAINT GREEN (1180 2805);
DISPLAY INVISIBLE (1180 2805);
FORCEPROP 2 LAST PATH I103
J 0
(1425 2950);
PAINT MONO (1425 2950);
DISPLAY INVISIBLE (1425 2950);
FORCEADD OFFPAGE..1
(-400 4225);
FORCEPROP 2 LAST $XR0 196 
J 0
(-682 4225);
DISPLAY 0.638298 (-682 4225);
PAINT MONO (-682 4225);
FORCEPROP 2 LAST CDS_LIB mstr_standard
J 1
(-400 4225);
PAINT ORANGE (-400 4225);
DISPLAY INVISIBLE (-400 4225);
FORCEPROP 1 LAST OFFPAGE TRUE
J 0
(-75 4100);
PAINT GREEN (-75 4100);
DISPLAY INVISIBLE (-75 4100);
FORCEPROP 1 LAST COMMENT_BODY TRUE
J 0
(-275 4125);
DISPLAY 0.978723 (-275 4125);
PAINT GREEN (-275 4125);
DISPLAY INVISIBLE (-275 4125);
FORCEPROP 2 LAST PATH I105
J 0
(-675 4275);
PAINT MONO (-675 4275);
DISPLAY INVISIBLE (-675 4275);
FORCEADD RES..2
(400 2725);
FORCEPROP 1 LAST LOCATION R9G26
J 0
(445 2850);
DISPLAY 0.617021 (445 2850);
PAINT AQUA (445 2850);
FORCEPROP 1 LAST PART_NUMBER G21796-010
J 0
(440 2600);
DISPLAY 0.617021 (440 2600);
PAINT BLUE (440 2600);
FORCEPROP 1 LAST VALUE 100.0K
J 0
(445 2800);
DISPLAY 0.617021 (445 2800);
PAINT SKYBLUE (445 2800);
FORCEPROP 1 LAST TOLERANCE 1%
J 0
(445 2750);
DISPLAY 0.617021 (445 2750);
PAINT SKYBLUE (445 2750);
FORCEPROP 1 LAST PACK_TYPE 0402
J 0
(440 2550);
DISPLAY 0.617021 (440 2550);
PAINT SKYBLUE (440 2550);
FORCEPROP 1 LAST MATERIAL CHIP
J 0
(440 2650);
DISPLAY 0.617021 (440 2650);
PAINT SKYBLUE (440 2650);
FORCEPROP 1 LAST WATTAGE 1/16W
J 0
(440 2700);
DISPLAY 0.617021 (440 2700);
PAINT SKYBLUE (440 2700);
FORCEPROP 1 LASTPIN (400 2625) $PN 2
J 0
(405 2635);
DISPLAY 0.617021 (405 2635);
PAINT ORANGE (405 2635);
FORCEPROP 1 LASTPIN (400 2825) $PN 1
J 0
(405 2787);
DISPLAY 0.617021 (405 2787);
PAINT ORANGE (405 2787);
FORCEPROP 2 LAST CDS_LIB mstr_discrete
J 0
(400 2725);
PAINT ORANGE (400 2725);
DISPLAY INVISIBLE (400 2725);
FORCEPROP 2 LAST SEC_TYPE 0402
J 0
(450 2950);
DISPLAY 1.021277 (450 2950);
PAINT ORANGE (450 2950);
DISPLAY INVISIBLE (450 2950);
FORCEPROP 2 LAST BOM_COST SM_HM
J 0
(450 2950);
DISPLAY 1.021277 (450 2950);
PAINT ORANGE (450 2950);
DISPLAY INVISIBLE (450 2950);
FORCEPROP 2 LAST SEC 1
J 0
(450 2950);
PAINT MONO (450 2950);
DISPLAY INVISIBLE (450 2950);
FORCEPROP 2 LAST CDS_LOCATION R9G26
J 0
(445 2850);
DISPLAY 0.617021 (445 2850);
PAINT AQUA (445 2850);
DISPLAY INVISIBLE (445 2850);
FORCEPROP 1 LAST PATH I106
J 0
(450 2900);
DISPLAY 0.978723 (450 2900);
PAINT WHITE (450 2900);
DISPLAY INVISIBLE (450 2900);
FORCEPROP 2 LAST ROOM BMC_VOLT_MONITOR
J 0
(450 2900);
DISPLAY 1.021277 (450 2900);
PAINT ORANGE (450 2900);
DISPLAY INVISIBLE (450 2900);
FORCEADD GND..1
(400 2500);
FORCEPROP 3 LASTPIN (400 2550) SIG_NAME GND\g
J 0
(410 2560);
DISPLAY 0.659574 (410 2560);
PAINT MONO (410 2560);
DISPLAY INVISIBLE (410 2560);
FORCEPROP 1 LAST VOLTAGE 0
J 0
(400 2500);
PAINT SKYBLUE (400 2500);
DISPLAY INVISIBLE (400 2500);
FORCEPROP 2 LAST CDS_LIB mstr_symbols
J 0
(400 2500);
PAINT ORANGE (400 2500);
DISPLAY INVISIBLE (400 2500);
FORCEPROP 1 LAST SIZE 1B
J 0
(475 2450);
DISPLAY 1.148936 (475 2450);
PAINT GREEN (475 2450);
DISPLAY INVISIBLE (475 2450);
FORCEPROP 1 LAST BODY_TYPE PLUMBING
J 0
(355 2457);
DISPLAY 0.340426 (355 2457);
PAINT GREEN (355 2457);
DISPLAY INVISIBLE (355 2457);
FORCEPROP 1 LAST PATH I107
J 0
(475 2500);
DISPLAY 1.212766 (475 2500);
PAINT GREEN (475 2500);
DISPLAY INVISIBLE (475 2500);
FORCEPROP 1 LAST HDL_POWER GND
J 0
(400 2650);
DISPLAY 1.148936 (400 2650);
PAINT GREEN (400 2650);
DISPLAY INVISIBLE (400 2650);
FORCEADD CAP..1
(800 2700);
FORCEPROP 1 LAST LOCATION C9G22
J 0
(850 2800);
DISPLAY 0.617021 (850 2800);
PAINT AQUA (850 2800);
FORCEPROP 1 LAST PART_NUMBER A36094-025
J 0
(850 2550);
DISPLAY 0.617021 (850 2550);
PAINT BLUE (850 2550);
FORCEPROP 1 LAST VALUE 10.0PF
J 0
(850 2750);
DISPLAY 0.617021 (850 2750);
PAINT SKYBLUE (850 2750);
FORCEPROP 1 LAST TOLERANCE 5%
J 0
(850 2650);
DISPLAY 0.617021 (850 2650);
PAINT SKYBLUE (850 2650);
FORCEPROP 1 LAST PACK_TYPE 0402LF
J 0
(850 2500);
DISPLAY 0.617021 (850 2500);
PAINT SKYBLUE (850 2500);
FORCEPROP 1 LAST VOLTAGE 50V
J 0
(850 2700);
DISPLAY 0.617021 (850 2700);
PAINT SKYBLUE (850 2700);
FORCEPROP 1 LAST MATERIAL COG
J 0
(850 2600);
DISPLAY 0.617021 (850 2600);
PAINT SKYBLUE (850 2600);
FORCEPROP 1 LASTPIN (800 2600) $PN 2
J 0
(810 2580);
DISPLAY 0.617021 (810 2580);
PAINT ORANGE (810 2580);
FORCEPROP 1 LASTPIN (800 2800) $PN 1
J 0
(810 2780);
DISPLAY 0.617021 (810 2780);
PAINT ORANGE (810 2780);
FORCEPROP 2 LAST CDS_LIB mstr_discrete
J 0
(800 2700);
PAINT ORANGE (800 2700);
DISPLAY INVISIBLE (800 2700);
FORCEPROP 2 LAST SEC_TYPE 0402LF
J 0
(850 2900);
DISPLAY 1.021277 (850 2900);
PAINT ORANGE (850 2900);
DISPLAY INVISIBLE (850 2900);
FORCEPROP 2 LAST BOM_COST SM_HM
J 0
(850 2900);
DISPLAY 1.021277 (850 2900);
PAINT ORANGE (850 2900);
DISPLAY INVISIBLE (850 2900);
FORCEPROP 2 LAST SEC 1
J 0
(850 2900);
DISPLAY 0.680851 (850 2900);
PAINT MONO (850 2900);
DISPLAY INVISIBLE (850 2900);
FORCEPROP 2 LAST CDS_LOCATION C9G22
J 0
(850 2800);
DISPLAY 0.617021 (850 2800);
PAINT AQUA (850 2800);
DISPLAY INVISIBLE (850 2800);
FORCEPROP 1 LAST PATH I108
J 0
(850 2850);
DISPLAY 0.978723 (850 2850);
PAINT WHITE (850 2850);
DISPLAY INVISIBLE (850 2850);
FORCEPROP 2 LAST ROOM BMC_VOLT_MONITOR
J 0
(850 2850);
DISPLAY 1.021277 (850 2850);
PAINT ORANGE (850 2850);
DISPLAY INVISIBLE (850 2850);
FORCEADD GND..1
(800 2500);
FORCEPROP 3 LASTPIN (800 2550) SIG_NAME GND\g
J 0
(810 2560);
DISPLAY 0.659574 (810 2560);
PAINT MONO (810 2560);
DISPLAY INVISIBLE (810 2560);
FORCEPROP 1 LAST VOLTAGE 0
J 0
(800 2500);
PAINT SKYBLUE (800 2500);
DISPLAY INVISIBLE (800 2500);
FORCEPROP 2 LAST CDS_LIB mstr_symbols
J 0
(800 2500);
PAINT ORANGE (800 2500);
DISPLAY INVISIBLE (800 2500);
FORCEPROP 1 LAST SIZE 1B
J 0
(875 2450);
DISPLAY 1.148936 (875 2450);
PAINT GREEN (875 2450);
DISPLAY INVISIBLE (875 2450);
FORCEPROP 1 LAST BODY_TYPE PLUMBING
J 0
(755 2457);
DISPLAY 0.340426 (755 2457);
PAINT GREEN (755 2457);
DISPLAY INVISIBLE (755 2457);
FORCEPROP 1 LAST PATH I109
J 0
(875 2500);
DISPLAY 1.212766 (875 2500);
PAINT GREEN (875 2500);
DISPLAY INVISIBLE (875 2500);
FORCEPROP 1 LAST HDL_POWER GND
J 0
(800 2650);
DISPLAY 1.148936 (800 2650);
PAINT GREEN (800 2650);
DISPLAY INVISIBLE (800 2650);
FORCEADD RES..2
(-4825 1425);
FORCEPROP 1 LAST LOCATION R1U38
J 0
(-4780 1550);
DISPLAY 0.617021 (-4780 1550);
PAINT AQUA (-4780 1550);
FORCEPROP 1 LAST PART_NUMBER G21796-345
J 0
(-4785 1300);
DISPLAY 0.617021 (-4785 1300);
PAINT BLUE (-4785 1300);
FORCEPROP 1 LAST VALUE 8.2K
J 0
(-4780 1500);
DISPLAY 0.617021 (-4780 1500);
PAINT SKYBLUE (-4780 1500);
FORCEPROP 1 LAST TOLERANCE 1%
J 0
(-4780 1450);
DISPLAY 0.617021 (-4780 1450);
PAINT SKYBLUE (-4780 1450);
FORCEPROP 1 LAST PACK_TYPE 0402
J 0
(-4785 1250);
DISPLAY 0.617021 (-4785 1250);
PAINT SKYBLUE (-4785 1250);
FORCEPROP 1 LAST MATERIAL CHIP
J 0
(-4785 1350);
DISPLAY 0.617021 (-4785 1350);
PAINT SKYBLUE (-4785 1350);
FORCEPROP 1 LAST WATTAGE 1/16W
J 0
(-4785 1400);
DISPLAY 0.617021 (-4785 1400);
PAINT SKYBLUE (-4785 1400);
FORCEPROP 1 LASTPIN (-4825 1325) $PN 2
J 0
(-4820 1335);
DISPLAY 0.617021 (-4820 1335);
PAINT MONO (-4820 1335);
FORCEPROP 1 LASTPIN (-4825 1525) $PN 1
J 0
(-4820 1487);
DISPLAY 0.617021 (-4820 1487);
PAINT MONO (-4820 1487);
FORCEPROP 2 LAST SEC_TYPE 0402
J 0
(-4775 1650);
PAINT MONO (-4775 1650);
DISPLAY INVISIBLE (-4775 1650);
FORCEPROP 2 LAST CDS_LIB mstr_discrete
J 0
(-4825 1425);
DISPLAY 1.361702 (-4825 1425);
PAINT ORANGE (-4825 1425);
DISPLAY INVISIBLE (-4825 1425);
FORCEPROP 2 LAST BOM_COST SM_HM
J 0
(-4775 1650);
DISPLAY 1.021277 (-4775 1650);
PAINT ORANGE (-4775 1650);
DISPLAY INVISIBLE (-4775 1650);
FORCEPROP 2 LAST SEC 1
J 0
(-4775 1650);
DISPLAY 0.936170 (-4775 1650);
PAINT MONO (-4775 1650);
DISPLAY INVISIBLE (-4775 1650);
FORCEPROP 2 LAST CDS_LOCATION R1U38
J 0
(-4780 1550);
DISPLAY 0.617021 (-4780 1550);
PAINT AQUA (-4780 1550);
DISPLAY INVISIBLE (-4780 1550);
FORCEPROP 1 LAST PATH I114
J 0
(-4775 1600);
DISPLAY 1.361702 (-4775 1600);
PAINT WHITE (-4775 1600);
DISPLAY INVISIBLE (-4775 1600);
FORCEPROP 2 LAST ROOM BMC_VOLT_MONITOR
J 0
(-4775 1600);
DISPLAY 1.021277 (-4775 1600);
PAINT ORANGE (-4775 1600);
DISPLAY INVISIBLE (-4775 1600);
FORCEADD RES..2
(-2850 1750);
FORCEPROP 1 LAST LOCATION R1U47
J 0
(-2805 1875);
DISPLAY 0.617021 (-2805 1875);
PAINT AQUA (-2805 1875);
FORCEPROP 1 LAST PART_NUMBER G21796-140
J 0
(-2810 1625);
DISPLAY 0.617021 (-2810 1625);
PAINT BLUE (-2810 1625);
FORCEPROP 1 LAST VALUE 5.11K
J 0
(-2805 1825);
DISPLAY 0.617021 (-2805 1825);
PAINT SKYBLUE (-2805 1825);
FORCEPROP 1 LAST TOLERANCE 1%
J 0
(-2805 1775);
DISPLAY 0.617021 (-2805 1775);
PAINT SKYBLUE (-2805 1775);
FORCEPROP 1 LAST PACK_TYPE 0402
J 0
(-2810 1575);
DISPLAY 0.617021 (-2810 1575);
PAINT SKYBLUE (-2810 1575);
FORCEPROP 1 LAST MATERIAL CHIP
J 0
(-2810 1675);
DISPLAY 0.617021 (-2810 1675);
PAINT SKYBLUE (-2810 1675);
FORCEPROP 1 LAST WATTAGE 1/16W
J 0
(-2810 1725);
DISPLAY 0.617021 (-2810 1725);
PAINT SKYBLUE (-2810 1725);
FORCEPROP 1 LASTPIN (-2850 1650) $PN 2
J 0
(-2845 1660);
DISPLAY 0.617021 (-2845 1660);
PAINT MONO (-2845 1660);
FORCEPROP 1 LASTPIN (-2850 1850) $PN 1
J 0
(-2845 1812);
DISPLAY 0.617021 (-2845 1812);
PAINT MONO (-2845 1812);
FORCEPROP 2 LAST SEC_TYPE 0402
J 0
(-2800 1975);
PAINT MONO (-2800 1975);
DISPLAY INVISIBLE (-2800 1975);
FORCEPROP 2 LAST CDS_LIB mstr_discrete
J 0
(-2850 1750);
DISPLAY 1.361702 (-2850 1750);
PAINT ORANGE (-2850 1750);
DISPLAY INVISIBLE (-2850 1750);
FORCEPROP 2 LAST BOM_COST SM_HM
J 0
(-2800 1975);
DISPLAY 1.021277 (-2800 1975);
PAINT ORANGE (-2800 1975);
DISPLAY INVISIBLE (-2800 1975);
FORCEPROP 2 LAST SEC 1
J 0
(-2800 1975);
DISPLAY 0.936170 (-2800 1975);
PAINT MONO (-2800 1975);
DISPLAY INVISIBLE (-2800 1975);
FORCEPROP 2 LAST CDS_LOCATION R1U47
J 0
(-2805 1875);
DISPLAY 0.617021 (-2805 1875);
PAINT AQUA (-2805 1875);
DISPLAY INVISIBLE (-2805 1875);
FORCEPROP 1 LAST PATH I115
J 0
(-2800 1925);
DISPLAY 1.361702 (-2800 1925);
PAINT WHITE (-2800 1925);
DISPLAY INVISIBLE (-2800 1925);
FORCEPROP 2 LAST ROOM BMC_VOLT_MONITOR
J 0
(-2800 1925);
DISPLAY 1.021277 (-2800 1925);
PAINT ORANGE (-2800 1925);
DISPLAY INVISIBLE (-2800 1925);
FORCEADD RES..2
(-2850 1350);
FORCEPROP 1 LAST LOCATION R1U44
J 0
(-2805 1475);
DISPLAY 0.617021 (-2805 1475);
PAINT AQUA (-2805 1475);
FORCEPROP 1 LAST PART_NUMBER G21796-279
J 0
(-2810 1225);
DISPLAY 0.617021 (-2810 1225);
PAINT BLUE (-2810 1225);
FORCEPROP 1 LAST VALUE 3.48K
J 0
(-2805 1425);
DISPLAY 0.617021 (-2805 1425);
PAINT SKYBLUE (-2805 1425);
FORCEPROP 1 LAST TOLERANCE 1.0%
J 0
(-2805 1375);
DISPLAY 0.617021 (-2805 1375);
PAINT SKYBLUE (-2805 1375);
FORCEPROP 1 LAST PACK_TYPE 0402
J 0
(-2810 1175);
DISPLAY 0.617021 (-2810 1175);
PAINT SKYBLUE (-2810 1175);
FORCEPROP 1 LAST MATERIAL CHIP
J 0
(-2810 1275);
DISPLAY 0.617021 (-2810 1275);
PAINT SKYBLUE (-2810 1275);
FORCEPROP 1 LAST WATTAGE 1/16W
J 0
(-2810 1325);
DISPLAY 0.617021 (-2810 1325);
PAINT SKYBLUE (-2810 1325);
FORCEPROP 1 LASTPIN (-2850 1250) $PN 2
J 0
(-2845 1260);
DISPLAY 0.617021 (-2845 1260);
PAINT MONO (-2845 1260);
FORCEPROP 1 LASTPIN (-2850 1450) $PN 1
J 0
(-2845 1412);
DISPLAY 0.617021 (-2845 1412);
PAINT MONO (-2845 1412);
FORCEPROP 2 LAST CDS_LIB mstr_discrete
J 0
(-2850 1350);
PAINT ORANGE (-2850 1350);
DISPLAY INVISIBLE (-2850 1350);
FORCEPROP 2 LAST BOM_COST SM_HM
J 0
(-2800 1575);
DISPLAY 1.021277 (-2800 1575);
PAINT ORANGE (-2800 1575);
DISPLAY INVISIBLE (-2800 1575);
FORCEPROP 2 LAST CDS_SEC 1
J 0
(-2800 1575);
DISPLAY 1.404255 (-2800 1575);
PAINT ORANGE (-2800 1575);
DISPLAY INVISIBLE (-2800 1575);
FORCEPROP 2 LAST $SEC 1
J 0
(-2800 1575);
DISPLAY 0.936170 (-2800 1575);
PAINT MONO (-2800 1575);
DISPLAY INVISIBLE (-2800 1575);
FORCEPROP 2 LAST CDS_LOCATION R1U44
J 0
(-2805 1475);
DISPLAY 0.617021 (-2805 1475);
PAINT AQUA (-2805 1475);
DISPLAY INVISIBLE (-2805 1475);
FORCEPROP 1 LAST PATH I116
J 0
(-2800 1525);
DISPLAY 1.361702 (-2800 1525);
PAINT WHITE (-2800 1525);
DISPLAY INVISIBLE (-2800 1525);
FORCEPROP 2 LAST ROOM BMC_VOLT_MONITOR
J 0
(-2800 1525);
DISPLAY 1.021277 (-2800 1525);
PAINT ORANGE (-2800 1525);
DISPLAY INVISIBLE (-2800 1525);
FORCEADD P5V_STBY..1
(-2850 1975);
FORCEPROP 3 LASTPIN (-2850 1925) SIG_NAME P5V_STBY\g
J 0
(-2840 1935);
DISPLAY 0.659574 (-2840 1935);
PAINT MONO (-2840 1935);
DISPLAY INVISIBLE (-2840 1935);
FORCEPROP 1 LAST VOLTAGE 5.0V
J 0
(-2895 1932);
DISPLAY 0.340426 (-2895 1932);
PAINT SKYBLUE (-2895 1932);
DISPLAY INVISIBLE (-2895 1932);
FORCEPROP 1 LAST SIZE 1B
J 0
(-2805 1997);
DISPLAY 0.340426 (-2805 1997);
PAINT GREEN (-2805 1997);
DISPLAY INVISIBLE (-2805 1997);
FORCEPROP 2 LAST CDS_LIB mstr_symbols
J 0
(-2850 1975);
PAINT ORANGE (-2850 1975);
DISPLAY INVISIBLE (-2850 1975);
FORCEPROP 1 LAST BODY_TYPE PLUMBING
J 0
(-2895 1932);
DISPLAY 0.340426 (-2895 1932);
PAINT GREEN (-2895 1932);
DISPLAY INVISIBLE (-2895 1932);
FORCEPROP 1 LAST PATH I119
J 0
(-2805 1977);
DISPLAY 0.340426 (-2805 1977);
PAINT GREEN (-2805 1977);
DISPLAY INVISIBLE (-2805 1977);
FORCEPROP 1 LAST HDL_POWER P5V_STBY
J 0
(-3150 1850);
DISPLAY 0.872340 (-3150 1850);
PAINT ORANGE (-3150 1850);
DISPLAY INVISIBLE (-3150 1850);
FORCEADD P1V05_PCH_STBY..1
(-4825 3775);
FORCEPROP 3 LASTPIN (-4825 3725) SIG_NAME P1V05_PCH_STBY\g
J 0
(-4815 3735);
DISPLAY 0.659574 (-4815 3735);
PAINT MONO (-4815 3735);
DISPLAY INVISIBLE (-4815 3735);
FORCEPROP 1 LAST VOLTAGE 1.05V
J 0
(-4870 3732);
DISPLAY 0.340426 (-4870 3732);
PAINT SKYBLUE (-4870 3732);
DISPLAY INVISIBLE (-4870 3732);
FORCEPROP 2 LAST CDS_LIB mstr_symbols
J 0
(-4825 3775);
PAINT ORANGE (-4825 3775);
DISPLAY INVISIBLE (-4825 3775);
FORCEPROP 1 LAST BODY_TYPE PLUMBING
J 0
(-4870 3732);
DISPLAY 0.340426 (-4870 3732);
PAINT GREEN (-4870 3732);
DISPLAY INVISIBLE (-4870 3732);
FORCEPROP 1 LAST PATH I121
J 0
(-4775 3800);
DISPLAY 0.872340 (-4775 3800);
PAINT AQUA (-4775 3800);
DISPLAY INVISIBLE (-4775 3800);
FORCEPROP 1 LAST HDL_POWER P1V05_PCH_STBY
J 0
(-4825 3825);
DISPLAY 0.872340 (-4825 3825);
PAINT GREEN (-4825 3825);
DISPLAY INVISIBLE (-4825 3825);
FORCEADD RES..2
(200 4025);
FORCEPROP 1 LAST LOCATION R1U50
J 0
(245 4150);
DISPLAY 0.617021 (245 4150);
PAINT AQUA (245 4150);
FORCEPROP 1 LAST PART_NUMBER G21796-080
J 0
(240 3900);
DISPLAY 0.617021 (240 3900);
PAINT BLUE (240 3900);
FORCEPROP 1 LAST VALUE 200.0K
J 0
(245 4100);
DISPLAY 0.617021 (245 4100);
PAINT SKYBLUE (245 4100);
FORCEPROP 1 LAST TOLERANCE 1%
J 0
(245 4050);
DISPLAY 0.617021 (245 4050);
PAINT SKYBLUE (245 4050);
FORCEPROP 1 LAST PACK_TYPE 0402
J 0
(240 3850);
DISPLAY 0.617021 (240 3850);
PAINT SKYBLUE (240 3850);
FORCEPROP 1 LAST MATERIAL CHIP
J 0
(240 3950);
DISPLAY 0.617021 (240 3950);
PAINT SKYBLUE (240 3950);
FORCEPROP 1 LAST WATTAGE 1/16W
J 0
(240 4000);
DISPLAY 0.617021 (240 4000);
PAINT SKYBLUE (240 4000);
FORCEPROP 1 LASTPIN (200 3925) $PN 2
J 0
(205 3935);
DISPLAY 0.617021 (205 3935);
PAINT ORANGE (205 3935);
FORCEPROP 1 LASTPIN (200 4125) $PN 1
J 0
(205 4087);
DISPLAY 0.617021 (205 4087);
PAINT ORANGE (205 4087);
FORCEPROP 2 LAST CDS_LIB mstr_discrete
J 0
(200 4025);
PAINT ORANGE (200 4025);
DISPLAY INVISIBLE (200 4025);
FORCEPROP 2 LAST SEC_TYPE 0402
J 0
(250 4250);
DISPLAY 1.021277 (250 4250);
PAINT ORANGE (250 4250);
DISPLAY INVISIBLE (250 4250);
FORCEPROP 2 LAST BOM_COST SM_HM
J 0
(250 4250);
DISPLAY 1.021277 (250 4250);
PAINT ORANGE (250 4250);
DISPLAY INVISIBLE (250 4250);
FORCEPROP 2 LAST SEC 1
J 0
(250 4250);
DISPLAY 0.680851 (250 4250);
PAINT MONO (250 4250);
DISPLAY INVISIBLE (250 4250);
FORCEPROP 2 LAST CDS_LOCATION R1U50
J 0
(245 4150);
DISPLAY 0.617021 (245 4150);
PAINT AQUA (245 4150);
DISPLAY INVISIBLE (245 4150);
FORCEPROP 1 LAST PATH I126
J 0
(250 4200);
DISPLAY 0.978723 (250 4200);
PAINT WHITE (250 4200);
DISPLAY INVISIBLE (250 4200);
FORCEPROP 2 LAST ROOM BMC_VOLT_MONITOR
J 0
(250 4200);
DISPLAY 1.021277 (250 4200);
PAINT ORANGE (250 4200);
DISPLAY INVISIBLE (250 4200);
FORCEADD P3V3_STBY..1
(-4825 2000);
FORCEPROP 3 LASTPIN (-4825 1950) SIG_NAME P3V3_STBY\g
J 0
(-4815 1960);
DISPLAY 0.659574 (-4815 1960);
PAINT MONO (-4815 1960);
DISPLAY INVISIBLE (-4815 1960);
FORCEPROP 1 LAST VOLTAGE 3.3V
J 0
(-4870 1957);
DISPLAY 0.340426 (-4870 1957);
PAINT SKYBLUE (-4870 1957);
DISPLAY INVISIBLE (-4870 1957);
FORCEPROP 1 LAST SIZE 1B
J 0
(-4780 2022);
DISPLAY 0.340426 (-4780 2022);
PAINT GREEN (-4780 2022);
DISPLAY INVISIBLE (-4780 2022);
FORCEPROP 2 LAST CDS_LIB mstr_symbols
J 0
(-4825 2000);
PAINT ORANGE (-4825 2000);
DISPLAY INVISIBLE (-4825 2000);
FORCEPROP 1 LAST BODY_TYPE PLUMBING
J 0
(-4870 1957);
DISPLAY 0.340426 (-4870 1957);
PAINT GREEN (-4870 1957);
DISPLAY INVISIBLE (-4870 1957);
FORCEPROP 1 LAST PATH I131
J 0
(-4780 2002);
DISPLAY 0.340426 (-4780 2002);
PAINT GREEN (-4780 2002);
DISPLAY INVISIBLE (-4780 2002);
FORCEPROP 1 LAST HDL_POWER P3V3_STBY
J 0
(-5125 1875);
DISPLAY 0.872340 (-5125 1875);
PAINT ORANGE (-5125 1875);
DISPLAY INVISIBLE (-5125 1875);
FORCEADD P12V_STBY..1
(-1125 2025);
FORCEPROP 3 LASTPIN (-1125 1975) SIG_NAME P12V_STBY\g
J 0
(-1115 1985);
DISPLAY 0.659574 (-1115 1985);
PAINT MONO (-1115 1985);
DISPLAY INVISIBLE (-1115 1985);
FORCEPROP 1 LAST VOLTAGE 12.0V
J 0
(-1170 1982);
DISPLAY 0.340426 (-1170 1982);
PAINT SKYBLUE (-1170 1982);
DISPLAY INVISIBLE (-1170 1982);
FORCEPROP 1 LAST SIZE 1B
J 0
(-1080 2047);
DISPLAY 0.340426 (-1080 2047);
PAINT GREEN (-1080 2047);
DISPLAY INVISIBLE (-1080 2047);
FORCEPROP 2 LAST CDS_LIB mstr_symbols
J 0
(-1125 2025);
PAINT ORANGE (-1125 2025);
DISPLAY INVISIBLE (-1125 2025);
FORCEPROP 1 LAST BODY_TYPE PLUMBING
J 0
(-1170 1982);
DISPLAY 0.340426 (-1170 1982);
PAINT GREEN (-1170 1982);
DISPLAY INVISIBLE (-1170 1982);
FORCEPROP 1 LAST PATH I132
J 0
(-1080 2027);
DISPLAY 0.340426 (-1080 2027);
PAINT GREEN (-1080 2027);
DISPLAY INVISIBLE (-1080 2027);
FORCEPROP 1 LAST HDL_POWER P12V_STBY
J 0
(-1425 1900);
DISPLAY 0.872340 (-1425 1900);
PAINT ORANGE (-1425 1900);
DISPLAY INVISIBLE (-1425 1900);
FORCEADD OFFPAGE..2
(-3950 4750);
FORCEPROP 2 LAST $XR0 147 
J 0
(-3761 4750);
DISPLAY 0.638298 (-3761 4750);
PAINT MONO (-3761 4750);
FORCEPROP 2 LAST $XR1 165 
J 0
(-3641 4750);
DISPLAY 0.638298 (-3641 4750);
PAINT MONO (-3641 4750);
FORCEPROP 2 LAST CDS_LIB mstr_standard
J 0
(-3950 4750);
PAINT ORANGE (-3950 4750);
DISPLAY INVISIBLE (-3950 4750);
FORCEPROP 1 LAST OFFPAGE TRUE
J 0
(-3625 4625);
PAINT GREEN (-3625 4625);
DISPLAY INVISIBLE (-3625 4625);
FORCEPROP 1 LAST COMMENT_BODY TRUE
J 0
(-3995 4655);
DISPLAY 1.170213 (-3995 4655);
PAINT GREEN (-3995 4655);
DISPLAY INVISIBLE (-3995 4655);
FORCEPROP 2 LAST PATH I138
J 0
(-3775 4825);
DISPLAY 1.021277 (-3775 4825);
PAINT ORANGE (-3775 4825);
DISPLAY INVISIBLE (-3775 4825);
FORCEADD CAP..1
(-4350 4550);
FORCEPROP 1 LAST LOCATION C9G15
J 0
(-4300 4650);
DISPLAY 0.617021 (-4300 4650);
PAINT AQUA (-4300 4650);
FORCEPROP 1 LAST PART_NUMBER A36095-025
J 0
(-4300 4400);
DISPLAY 0.617021 (-4300 4400);
PAINT BLUE (-4300 4400);
FORCEPROP 1 LAST VALUE 47.0PF
J 0
(-4300 4600);
DISPLAY 0.617021 (-4300 4600);
PAINT SKYBLUE (-4300 4600);
FORCEPROP 1 LAST TOLERANCE 5%
J 0
(-4300 4500);
DISPLAY 0.617021 (-4300 4500);
PAINT SKYBLUE (-4300 4500);
FORCEPROP 1 LAST PACK_TYPE 0402LF
J 0
(-4300 4350);
DISPLAY 0.617021 (-4300 4350);
PAINT SKYBLUE (-4300 4350);
FORCEPROP 1 LAST VOLTAGE 50V
J 0
(-4300 4550);
DISPLAY 0.617021 (-4300 4550);
PAINT SKYBLUE (-4300 4550);
FORCEPROP 1 LAST MATERIAL COG
J 0
(-4300 4450);
DISPLAY 0.617021 (-4300 4450);
PAINT SKYBLUE (-4300 4450);
FORCEPROP 1 LASTPIN (-4350 4450) $PN 2
J 0
(-4340 4430);
DISPLAY 0.617021 (-4340 4430);
PAINT ORANGE (-4340 4430);
FORCEPROP 1 LASTPIN (-4350 4650) $PN 1
J 0
(-4340 4630);
DISPLAY 0.617021 (-4340 4630);
PAINT ORANGE (-4340 4630);
FORCEPROP 2 LAST SEC_TYPE 0402LF
J 0
(-4300 4750);
DISPLAY 1.021277 (-4300 4750);
PAINT ORANGE (-4300 4750);
DISPLAY INVISIBLE (-4300 4750);
FORCEPROP 2 LAST CDS_LIB mstr_discrete
J 0
(-4350 4550);
PAINT ORANGE (-4350 4550);
DISPLAY INVISIBLE (-4350 4550);
FORCEPROP 2 LAST BOM_COST SM_HM
J 0
(-4300 4750);
DISPLAY 1.021277 (-4300 4750);
PAINT ORANGE (-4300 4750);
DISPLAY INVISIBLE (-4300 4750);
FORCEPROP 2 LAST SEC 1
J 0
(-4300 4750);
DISPLAY 0.680851 (-4300 4750);
PAINT MONO (-4300 4750);
DISPLAY INVISIBLE (-4300 4750);
FORCEPROP 2 LAST CDS_LOCATION C9G15
J 0
(-4300 4650);
DISPLAY 0.617021 (-4300 4650);
PAINT AQUA (-4300 4650);
DISPLAY INVISIBLE (-4300 4650);
FORCEPROP 1 LAST PATH I139
J 0
(-4300 4700);
DISPLAY 0.978723 (-4300 4700);
PAINT WHITE (-4300 4700);
DISPLAY INVISIBLE (-4300 4700);
FORCEPROP 2 LAST ROOM BMC_VOLT_MONITOR
J 0
(-4300 4700);
DISPLAY 1.021277 (-4300 4700);
PAINT ORANGE (-4300 4700);
DISPLAY INVISIBLE (-4300 4700);
FORCEADD RES..2
(-4700 4950);
FORCEPROP 1 LAST LOCATION R1U29
J 0
(-4655 5075);
DISPLAY 0.617021 (-4655 5075);
PAINT AQUA (-4655 5075);
FORCEPROP 1 LAST PART_NUMBER G21796-140
J 0
(-4660 4825);
DISPLAY 0.617021 (-4660 4825);
PAINT BLUE (-4660 4825);
FORCEPROP 1 LAST VALUE 5.11K
J 0
(-4655 5025);
DISPLAY 0.617021 (-4655 5025);
PAINT SKYBLUE (-4655 5025);
FORCEPROP 1 LAST TOLERANCE 1%
J 0
(-4655 4975);
DISPLAY 0.617021 (-4655 4975);
PAINT SKYBLUE (-4655 4975);
FORCEPROP 1 LAST PACK_TYPE 0402
J 0
(-4660 4775);
DISPLAY 0.617021 (-4660 4775);
PAINT SKYBLUE (-4660 4775);
FORCEPROP 1 LAST MATERIAL CHIP
J 0
(-4660 4875);
DISPLAY 0.617021 (-4660 4875);
PAINT SKYBLUE (-4660 4875);
FORCEPROP 1 LAST WATTAGE 1/16W
J 0
(-4660 4925);
DISPLAY 0.617021 (-4660 4925);
PAINT SKYBLUE (-4660 4925);
FORCEPROP 1 LASTPIN (-4700 4850) $PN 2
J 0
(-4695 4860);
DISPLAY 0.617021 (-4695 4860);
PAINT ORANGE (-4695 4860);
FORCEPROP 1 LASTPIN (-4700 5050) $PN 1
J 0
(-4695 5012);
DISPLAY 0.617021 (-4695 5012);
PAINT ORANGE (-4695 5012);
FORCEPROP 2 LAST BOM_COST SM_HM
J 0
(-4650 5175);
DISPLAY 1.021277 (-4650 5175);
PAINT ORANGE (-4650 5175);
DISPLAY INVISIBLE (-4650 5175);
FORCEPROP 2 LAST CDS_LIB mstr_discrete
J 0
(-4700 4950);
PAINT ORANGE (-4700 4950);
DISPLAY INVISIBLE (-4700 4950);
FORCEPROP 2 LAST SEC_TYPE 0402
J 0
(-4650 5175);
DISPLAY 1.021277 (-4650 5175);
PAINT ORANGE (-4650 5175);
DISPLAY INVISIBLE (-4650 5175);
FORCEPROP 2 LAST SEC 1
J 0
(-4650 5175);
DISPLAY 0.680851 (-4650 5175);
PAINT MONO (-4650 5175);
DISPLAY INVISIBLE (-4650 5175);
FORCEPROP 2 LAST CDS_LOCATION R1U29
J 0
(-4655 5075);
DISPLAY 0.617021 (-4655 5075);
PAINT AQUA (-4655 5075);
DISPLAY INVISIBLE (-4655 5075);
FORCEPROP 1 LAST PATH I141
J 0
(-4650 5125);
DISPLAY 0.978723 (-4650 5125);
PAINT WHITE (-4650 5125);
DISPLAY INVISIBLE (-4650 5125);
FORCEPROP 2 LAST ROOM BMC_VOLT_MONITOR
J 0
(-4650 5125);
DISPLAY 1.021277 (-4650 5125);
PAINT ORANGE (-4650 5125);
DISPLAY INVISIBLE (-4650 5125);
FORCEADD RES..2
(-4700 4550);
FORCEPROP 1 LAST LOCATION R1U28
J 0
(-4655 4675);
DISPLAY 0.617021 (-4655 4675);
PAINT AQUA (-4655 4675);
FORCEPROP 1 LAST PART_NUMBER G21796-279
J 0
(-4660 4425);
DISPLAY 0.617021 (-4660 4425);
PAINT BLUE (-4660 4425);
FORCEPROP 1 LAST VALUE 3.48K
J 0
(-4655 4625);
DISPLAY 0.617021 (-4655 4625);
PAINT SKYBLUE (-4655 4625);
FORCEPROP 1 LAST TOLERANCE 1.0%
J 0
(-4655 4575);
DISPLAY 0.617021 (-4655 4575);
PAINT SKYBLUE (-4655 4575);
FORCEPROP 1 LAST PACK_TYPE 0402
J 0
(-4660 4375);
DISPLAY 0.617021 (-4660 4375);
PAINT SKYBLUE (-4660 4375);
FORCEPROP 1 LAST MATERIAL CHIP
J 0
(-4660 4475);
DISPLAY 0.617021 (-4660 4475);
PAINT SKYBLUE (-4660 4475);
FORCEPROP 1 LAST WATTAGE 1/16W
J 0
(-4660 4525);
DISPLAY 0.617021 (-4660 4525);
PAINT SKYBLUE (-4660 4525);
FORCEPROP 1 LASTPIN (-4700 4450) $PN 2
J 0
(-4695 4460);
DISPLAY 0.617021 (-4695 4460);
PAINT ORANGE (-4695 4460);
FORCEPROP 1 LASTPIN (-4700 4650) $PN 1
J 0
(-4695 4612);
DISPLAY 0.617021 (-4695 4612);
PAINT ORANGE (-4695 4612);
FORCEPROP 2 LAST BOM_COST SM_HM
J 0
(-4650 4775);
DISPLAY 1.021277 (-4650 4775);
PAINT ORANGE (-4650 4775);
DISPLAY INVISIBLE (-4650 4775);
FORCEPROP 2 LAST CDS_LIB mstr_discrete
J 0
(-4700 4550);
PAINT ORANGE (-4700 4550);
DISPLAY INVISIBLE (-4700 4550);
FORCEPROP 2 LAST SEC_TYPE 0402
J 0
(-4650 4775);
DISPLAY 1.021277 (-4650 4775);
PAINT ORANGE (-4650 4775);
DISPLAY INVISIBLE (-4650 4775);
FORCEPROP 2 LAST SEC 1
J 0
(-4650 4775);
DISPLAY 0.680851 (-4650 4775);
PAINT MONO (-4650 4775);
DISPLAY INVISIBLE (-4650 4775);
FORCEPROP 2 LAST CDS_LOCATION R1U28
J 0
(-4655 4675);
DISPLAY 0.617021 (-4655 4675);
PAINT AQUA (-4655 4675);
DISPLAY INVISIBLE (-4655 4675);
FORCEPROP 1 LAST PATH I142
J 0
(-4650 4725);
DISPLAY 0.978723 (-4650 4725);
PAINT WHITE (-4650 4725);
DISPLAY INVISIBLE (-4650 4725);
FORCEPROP 2 LAST ROOM BMC_VOLT_MONITOR
J 0
(-4650 4725);
DISPLAY 1.021277 (-4650 4725);
PAINT ORANGE (-4650 4725);
DISPLAY INVISIBLE (-4650 4725);
FORCEADD GND..1
(-4700 4300);
FORCEPROP 3 LASTPIN (-4700 4350) SIG_NAME GND\g
J 0
(-4690 4360);
DISPLAY 0.659574 (-4690 4360);
PAINT MONO (-4690 4360);
DISPLAY INVISIBLE (-4690 4360);
FORCEPROP 1 LAST VOLTAGE 0
J 0
(-4700 4300);
PAINT SKYBLUE (-4700 4300);
DISPLAY INVISIBLE (-4700 4300);
FORCEPROP 1 LAST SIZE 1B
J 0
(-4625 4250);
DISPLAY 1.148936 (-4625 4250);
PAINT GREEN (-4625 4250);
DISPLAY INVISIBLE (-4625 4250);
FORCEPROP 2 LAST CDS_LIB mstr_symbols
J 0
(-4700 4300);
PAINT ORANGE (-4700 4300);
DISPLAY INVISIBLE (-4700 4300);
FORCEPROP 1 LAST BODY_TYPE PLUMBING
J 0
(-4745 4257);
DISPLAY 0.340426 (-4745 4257);
PAINT GREEN (-4745 4257);
DISPLAY INVISIBLE (-4745 4257);
FORCEPROP 1 LAST PATH I143
J 0
(-4625 4300);
DISPLAY 0.872340 (-4625 4300);
PAINT AQUA (-4625 4300);
DISPLAY INVISIBLE (-4625 4300);
FORCEPROP 1 LAST HDL_POWER GND
J 0
(-4700 4450);
DISPLAY 1.148936 (-4700 4450);
PAINT GREEN (-4700 4450);
DISPLAY INVISIBLE (-4700 4450);
FORCEADD P5V..1
(-4700 5175);
FORCEPROP 3 LASTPIN (-4700 5125) SIG_NAME P5V\g
J 0
(-4690 5135);
DISPLAY 0.659574 (-4690 5135);
PAINT MONO (-4690 5135);
DISPLAY INVISIBLE (-4690 5135);
FORCEPROP 1 LAST VOLTAGE 5.0V
J 0
(-4745 5132);
DISPLAY 0.340426 (-4745 5132);
PAINT SKYBLUE (-4745 5132);
DISPLAY INVISIBLE (-4745 5132);
FORCEPROP 1 LAST SIZE 1B
J 0
(-4655 5197);
DISPLAY 0.340426 (-4655 5197);
PAINT GREEN (-4655 5197);
DISPLAY INVISIBLE (-4655 5197);
FORCEPROP 2 LAST CDS_LIB mstr_symbols
J 0
(-4700 5175);
PAINT ORANGE (-4700 5175);
DISPLAY INVISIBLE (-4700 5175);
FORCEPROP 1 LAST BODY_TYPE PLUMBING
J 0
(-4745 5132);
DISPLAY 0.340426 (-4745 5132);
PAINT GREEN (-4745 5132);
DISPLAY INVISIBLE (-4745 5132);
FORCEPROP 1 LAST PATH I144
J 0
(-4655 5177);
DISPLAY 0.340426 (-4655 5177);
PAINT GREEN (-4655 5177);
DISPLAY INVISIBLE (-4655 5177);
FORCEPROP 1 LAST HDL_POWER P5V
J 0
(-5000 5050);
DISPLAY 0.872340 (-5000 5050);
PAINT ORANGE (-5000 5050);
DISPLAY INVISIBLE (-5000 5050);
FORCEADD OFFPAGE..2
(-2050 4800);
FORCEPROP 2 LAST $XR0 147 
J 0
(-1861 4800);
DISPLAY 0.638298 (-1861 4800);
PAINT MONO (-1861 4800);
FORCEPROP 2 LAST $XR1 165 
J 0
(-1741 4800);
DISPLAY 0.638298 (-1741 4800);
PAINT MONO (-1741 4800);
FORCEPROP 2 LAST CDS_LIB mstr_standard
J 0
(-2050 4800);
PAINT ORANGE (-2050 4800);
DISPLAY INVISIBLE (-2050 4800);
FORCEPROP 1 LAST OFFPAGE TRUE
J 0
(-1725 4675);
PAINT GREEN (-1725 4675);
DISPLAY INVISIBLE (-1725 4675);
FORCEPROP 1 LAST COMMENT_BODY TRUE
J 0
(-2095 4705);
DISPLAY 1.170213 (-2095 4705);
PAINT GREEN (-2095 4705);
DISPLAY INVISIBLE (-2095 4705);
FORCEPROP 2 LAST PATH I145
J 0
(-1875 4875);
DISPLAY 1.021277 (-1875 4875);
PAINT ORANGE (-1875 4875);
DISPLAY INVISIBLE (-1875 4875);
FORCEADD CAP..1
(-2550 4600);
FORCEPROP 1 LAST LOCATION C9G14
J 0
(-2500 4700);
DISPLAY 0.617021 (-2500 4700);
PAINT AQUA (-2500 4700);
FORCEPROP 1 LAST PART_NUMBER A36095-025
J 0
(-2500 4450);
DISPLAY 0.617021 (-2500 4450);
PAINT BLUE (-2500 4450);
FORCEPROP 1 LAST VALUE 47.0PF
J 0
(-2500 4650);
DISPLAY 0.617021 (-2500 4650);
PAINT SKYBLUE (-2500 4650);
FORCEPROP 1 LAST TOLERANCE 5%
J 0
(-2500 4550);
DISPLAY 0.617021 (-2500 4550);
PAINT SKYBLUE (-2500 4550);
FORCEPROP 1 LAST PACK_TYPE 0402LF
J 0
(-2500 4400);
DISPLAY 0.617021 (-2500 4400);
PAINT SKYBLUE (-2500 4400);
FORCEPROP 1 LAST VOLTAGE 50V
J 0
(-2500 4600);
DISPLAY 0.617021 (-2500 4600);
PAINT SKYBLUE (-2500 4600);
FORCEPROP 1 LAST MATERIAL COG
J 0
(-2500 4500);
DISPLAY 0.617021 (-2500 4500);
PAINT SKYBLUE (-2500 4500);
FORCEPROP 1 LASTPIN (-2550 4500) $PN 2
J 0
(-2540 4480);
DISPLAY 0.617021 (-2540 4480);
PAINT ORANGE (-2540 4480);
FORCEPROP 1 LASTPIN (-2550 4700) $PN 1
J 0
(-2540 4680);
DISPLAY 0.617021 (-2540 4680);
PAINT ORANGE (-2540 4680);
FORCEPROP 2 LAST SEC_TYPE 0402LF
J 0
(-2500 4800);
DISPLAY 1.021277 (-2500 4800);
PAINT ORANGE (-2500 4800);
DISPLAY INVISIBLE (-2500 4800);
FORCEPROP 2 LAST CDS_LIB mstr_discrete
J 0
(-2550 4600);
PAINT ORANGE (-2550 4600);
DISPLAY INVISIBLE (-2550 4600);
FORCEPROP 2 LAST BOM_COST SM_HM
J 0
(-2500 4800);
DISPLAY 1.021277 (-2500 4800);
PAINT ORANGE (-2500 4800);
DISPLAY INVISIBLE (-2500 4800);
FORCEPROP 2 LAST SEC 1
J 0
(-2500 4800);
DISPLAY 0.680851 (-2500 4800);
PAINT MONO (-2500 4800);
DISPLAY INVISIBLE (-2500 4800);
FORCEPROP 2 LAST CDS_LOCATION C9G14
J 0
(-2500 4700);
DISPLAY 0.617021 (-2500 4700);
PAINT AQUA (-2500 4700);
DISPLAY INVISIBLE (-2500 4700);
FORCEPROP 1 LAST PATH I146
J 0
(-2500 4750);
DISPLAY 0.978723 (-2500 4750);
PAINT WHITE (-2500 4750);
DISPLAY INVISIBLE (-2500 4750);
FORCEPROP 2 LAST ROOM BMC_VOLT_MONITOR
J 0
(-2500 4750);
DISPLAY 1.021277 (-2500 4750);
PAINT ORANGE (-2500 4750);
DISPLAY INVISIBLE (-2500 4750);
FORCEADD RES..2
(-2875 5000);
FORCEPROP 1 LAST LOCATION R1U26
J 0
(-2830 5125);
DISPLAY 0.617021 (-2830 5125);
PAINT AQUA (-2830 5125);
FORCEPROP 1 LAST PART_NUMBER G21796-140
J 0
(-2835 4875);
DISPLAY 0.617021 (-2835 4875);
PAINT BLUE (-2835 4875);
FORCEPROP 1 LAST VALUE 5.11K
J 0
(-2830 5075);
DISPLAY 0.617021 (-2830 5075);
PAINT SKYBLUE (-2830 5075);
FORCEPROP 1 LAST TOLERANCE 1%
J 0
(-2830 5025);
DISPLAY 0.617021 (-2830 5025);
PAINT SKYBLUE (-2830 5025);
FORCEPROP 1 LAST PACK_TYPE 0402
J 0
(-2835 4825);
DISPLAY 0.617021 (-2835 4825);
PAINT SKYBLUE (-2835 4825);
FORCEPROP 1 LAST MATERIAL CHIP
J 0
(-2835 4925);
DISPLAY 0.617021 (-2835 4925);
PAINT SKYBLUE (-2835 4925);
FORCEPROP 1 LAST WATTAGE 1/16W
J 0
(-2835 4975);
DISPLAY 0.617021 (-2835 4975);
PAINT SKYBLUE (-2835 4975);
FORCEPROP 1 LASTPIN (-2875 4900) $PN 2
J 0
(-2870 4910);
DISPLAY 0.617021 (-2870 4910);
PAINT ORANGE (-2870 4910);
FORCEPROP 1 LASTPIN (-2875 5100) $PN 1
J 0
(-2870 5062);
DISPLAY 0.617021 (-2870 5062);
PAINT ORANGE (-2870 5062);
FORCEPROP 2 LAST BOM_COST SM_HM
J 0
(-2825 5225);
DISPLAY 1.021277 (-2825 5225);
PAINT ORANGE (-2825 5225);
DISPLAY INVISIBLE (-2825 5225);
FORCEPROP 2 LAST CDS_LIB mstr_discrete
J 0
(-2875 5000);
PAINT ORANGE (-2875 5000);
DISPLAY INVISIBLE (-2875 5000);
FORCEPROP 2 LAST SEC_TYPE 0402
J 0
(-2825 5225);
DISPLAY 1.021277 (-2825 5225);
PAINT ORANGE (-2825 5225);
DISPLAY INVISIBLE (-2825 5225);
FORCEPROP 2 LAST SEC 1
J 0
(-2825 5225);
DISPLAY 0.680851 (-2825 5225);
PAINT MONO (-2825 5225);
DISPLAY INVISIBLE (-2825 5225);
FORCEPROP 2 LAST CDS_LOCATION R1U26
J 0
(-2830 5125);
DISPLAY 0.617021 (-2830 5125);
PAINT AQUA (-2830 5125);
DISPLAY INVISIBLE (-2830 5125);
FORCEPROP 1 LAST PATH I148
J 0
(-2825 5175);
DISPLAY 0.978723 (-2825 5175);
PAINT WHITE (-2825 5175);
DISPLAY INVISIBLE (-2825 5175);
FORCEPROP 2 LAST ROOM BMC_VOLT_MONITOR
J 0
(-2825 5175);
DISPLAY 1.021277 (-2825 5175);
PAINT ORANGE (-2825 5175);
DISPLAY INVISIBLE (-2825 5175);
FORCEADD RES..2
(-2875 4625);
FORCEPROP 1 LAST LOCATION R1U27
J 0
(-2830 4750);
DISPLAY 0.617021 (-2830 4750);
PAINT AQUA (-2830 4750);
FORCEPROP 1 LAST PART_NUMBER G21796-345
J 0
(-2835 4500);
DISPLAY 0.617021 (-2835 4500);
PAINT BLUE (-2835 4500);
FORCEPROP 1 LAST VALUE 8.2K
J 0
(-2830 4700);
DISPLAY 0.617021 (-2830 4700);
PAINT SKYBLUE (-2830 4700);
FORCEPROP 1 LAST TOLERANCE 1%
J 0
(-2830 4650);
DISPLAY 0.617021 (-2830 4650);
PAINT SKYBLUE (-2830 4650);
FORCEPROP 1 LAST PACK_TYPE 0402
J 0
(-2835 4450);
DISPLAY 0.617021 (-2835 4450);
PAINT SKYBLUE (-2835 4450);
FORCEPROP 1 LAST MATERIAL CHIP
J 0
(-2835 4550);
DISPLAY 0.617021 (-2835 4550);
PAINT SKYBLUE (-2835 4550);
FORCEPROP 1 LAST WATTAGE 1/16W
J 0
(-2835 4600);
DISPLAY 0.617021 (-2835 4600);
PAINT SKYBLUE (-2835 4600);
FORCEPROP 1 LASTPIN (-2875 4525) $PN 2
J 0
(-2870 4535);
DISPLAY 0.617021 (-2870 4535);
PAINT ORANGE (-2870 4535);
FORCEPROP 1 LASTPIN (-2875 4725) $PN 1
J 0
(-2870 4687);
DISPLAY 0.617021 (-2870 4687);
PAINT ORANGE (-2870 4687);
FORCEPROP 2 LAST BOM_COST SM_HM
J 0
(-2825 4850);
DISPLAY 1.021277 (-2825 4850);
PAINT ORANGE (-2825 4850);
DISPLAY INVISIBLE (-2825 4850);
FORCEPROP 2 LAST CDS_LIB mstr_discrete
J 0
(-2875 4625);
PAINT ORANGE (-2875 4625);
DISPLAY INVISIBLE (-2875 4625);
FORCEPROP 2 LAST SEC_TYPE 0402
J 0
(-2825 4850);
DISPLAY 1.021277 (-2825 4850);
PAINT ORANGE (-2825 4850);
DISPLAY INVISIBLE (-2825 4850);
FORCEPROP 2 LAST SEC 1
J 0
(-2825 4850);
DISPLAY 0.680851 (-2825 4850);
PAINT MONO (-2825 4850);
DISPLAY INVISIBLE (-2825 4850);
FORCEPROP 2 LAST CDS_LOCATION R1U27
J 0
(-2830 4750);
DISPLAY 0.617021 (-2830 4750);
PAINT AQUA (-2830 4750);
DISPLAY INVISIBLE (-2830 4750);
FORCEPROP 1 LAST PATH I149
J 0
(-2825 4800);
DISPLAY 0.978723 (-2825 4800);
PAINT WHITE (-2825 4800);
DISPLAY INVISIBLE (-2825 4800);
FORCEPROP 2 LAST ROOM BMC_VOLT_MONITOR
J 0
(-2825 4800);
DISPLAY 1.021277 (-2825 4800);
PAINT ORANGE (-2825 4800);
DISPLAY INVISIBLE (-2825 4800);
FORCEADD GND..1
(-2875 4350);
FORCEPROP 3 LASTPIN (-2875 4400) SIG_NAME GND\g
J 0
(-2865 4410);
DISPLAY 0.659574 (-2865 4410);
PAINT MONO (-2865 4410);
DISPLAY INVISIBLE (-2865 4410);
FORCEPROP 1 LAST VOLTAGE 0
J 0
(-2875 4350);
PAINT SKYBLUE (-2875 4350);
DISPLAY INVISIBLE (-2875 4350);
FORCEPROP 1 LAST SIZE 1B
J 0
(-2800 4300);
DISPLAY 1.148936 (-2800 4300);
PAINT GREEN (-2800 4300);
DISPLAY INVISIBLE (-2800 4300);
FORCEPROP 2 LAST CDS_LIB mstr_symbols
J 0
(-2875 4350);
PAINT ORANGE (-2875 4350);
DISPLAY INVISIBLE (-2875 4350);
FORCEPROP 1 LAST BODY_TYPE PLUMBING
J 0
(-2920 4307);
DISPLAY 0.340426 (-2920 4307);
PAINT GREEN (-2920 4307);
DISPLAY INVISIBLE (-2920 4307);
FORCEPROP 1 LAST PATH I150
J 0
(-2800 4350);
DISPLAY 0.872340 (-2800 4350);
PAINT AQUA (-2800 4350);
DISPLAY INVISIBLE (-2800 4350);
FORCEPROP 1 LAST HDL_POWER GND
J 0
(-2875 4500);
DISPLAY 1.148936 (-2875 4500);
PAINT GREEN (-2875 4500);
DISPLAY INVISIBLE (-2875 4500);
FORCEADD P3V3..1
(-2875 5200);
FORCEPROP 3 LASTPIN (-2875 5150) SIG_NAME P3V3\g
J 0
(-2865 5160);
DISPLAY 0.659574 (-2865 5160);
PAINT MONO (-2865 5160);
DISPLAY INVISIBLE (-2865 5160);
FORCEPROP 1 LAST VOLTAGE 3.3V
J 0
(-2920 5157);
DISPLAY 0.340426 (-2920 5157);
PAINT SKYBLUE (-2920 5157);
DISPLAY INVISIBLE (-2920 5157);
FORCEPROP 1 LAST SIZE 1B
J 0
(-2830 5222);
DISPLAY 0.340426 (-2830 5222);
PAINT GREEN (-2830 5222);
DISPLAY INVISIBLE (-2830 5222);
FORCEPROP 2 LAST CDS_LIB mstr_symbols
J 0
(-2875 5200);
PAINT ORANGE (-2875 5200);
DISPLAY INVISIBLE (-2875 5200);
FORCEPROP 1 LAST BODY_TYPE PLUMBING
J 0
(-2920 5157);
DISPLAY 0.340426 (-2920 5157);
PAINT GREEN (-2920 5157);
DISPLAY INVISIBLE (-2920 5157);
FORCEPROP 1 LAST PATH I151
J 0
(-2830 5202);
DISPLAY 0.340426 (-2830 5202);
PAINT GREEN (-2830 5202);
DISPLAY INVISIBLE (-2830 5202);
FORCEPROP 1 LAST HDL_POWER P3V3
J 0
(-3200 5075);
DISPLAY 0.872340 (-3200 5075);
PAINT ORANGE (-3200 5075);
DISPLAY INVISIBLE (-3200 5075);
FORCEADD OFFPAGE..2
(1650 1650);
FORCEPROP 2 LAST $XR0 147 
J 0
(1839 1650);
DISPLAY 0.638298 (1839 1650);
PAINT MONO (1839 1650);
FORCEPROP 2 LAST $XR1 165 
J 0
(1959 1650);
DISPLAY 0.638298 (1959 1650);
PAINT MONO (1959 1650);
FORCEPROP 2 LAST CDS_LIB mstr_standard
J 0
(1650 1650);
DISPLAY 1.361702 (1650 1650);
PAINT ORANGE (1650 1650);
DISPLAY INVISIBLE (1650 1650);
FORCEPROP 1 LAST OFFPAGE TRUE
J 0
(1975 1525);
PAINT GREEN (1975 1525);
DISPLAY INVISIBLE (1975 1525);
FORCEPROP 1 LAST COMMENT_BODY TRUE
J 0
(1605 1555);
DISPLAY 1.170213 (1605 1555);
PAINT GREEN (1605 1555);
DISPLAY INVISIBLE (1605 1555);
FORCEPROP 2 LAST PATH I152
J 0
(1850 1700);
DISPLAY 1.021277 (1850 1700);
PAINT ORANGE (1850 1700);
DISPLAY INVISIBLE (1850 1700);
FORCEADD CAP..1
(800 1475);
FORCEPROP 1 LAST LOCATION C9G18
J 0
(850 1575);
DISPLAY 0.617021 (850 1575);
PAINT AQUA (850 1575);
FORCEPROP 1 LAST PART_NUMBER A36095-025
J 0
(850 1325);
DISPLAY 0.617021 (850 1325);
PAINT BLUE (850 1325);
FORCEPROP 1 LAST VALUE 47.0PF
J 0
(850 1525);
DISPLAY 0.617021 (850 1525);
PAINT SKYBLUE (850 1525);
FORCEPROP 1 LAST TOLERANCE 5%
J 0
(850 1425);
DISPLAY 0.617021 (850 1425);
PAINT SKYBLUE (850 1425);
FORCEPROP 1 LAST PACK_TYPE 0402LF
J 0
(850 1275);
DISPLAY 0.617021 (850 1275);
PAINT SKYBLUE (850 1275);
FORCEPROP 1 LAST VOLTAGE 50V
J 0
(850 1475);
DISPLAY 0.617021 (850 1475);
PAINT SKYBLUE (850 1475);
FORCEPROP 1 LAST MATERIAL COG
J 0
(850 1375);
DISPLAY 0.617021 (850 1375);
PAINT SKYBLUE (850 1375);
FORCEPROP 1 LASTPIN (800 1375) $PN 2
J 0
(810 1355);
DISPLAY 0.617021 (810 1355);
PAINT MONO (810 1355);
FORCEPROP 1 LASTPIN (800 1575) $PN 1
J 0
(810 1555);
DISPLAY 0.617021 (810 1555);
PAINT MONO (810 1555);
FORCEPROP 2 LAST SEC_TYPE 0402LF
J 0
(850 1675);
PAINT MONO (850 1675);
DISPLAY INVISIBLE (850 1675);
FORCEPROP 2 LAST CDS_LIB mstr_discrete
J 0
(800 1475);
DISPLAY 1.361702 (800 1475);
PAINT ORANGE (800 1475);
DISPLAY INVISIBLE (800 1475);
FORCEPROP 2 LAST BOM_COST SM_HM
J 0
(850 1675);
DISPLAY 1.021277 (850 1675);
PAINT ORANGE (850 1675);
DISPLAY INVISIBLE (850 1675);
FORCEPROP 2 LAST SEC 1
J 0
(850 1675);
DISPLAY 0.936170 (850 1675);
PAINT MONO (850 1675);
DISPLAY INVISIBLE (850 1675);
FORCEPROP 2 LAST CDS_LOCATION C9G18
J 0
(850 1575);
DISPLAY 0.617021 (850 1575);
PAINT AQUA (850 1575);
DISPLAY INVISIBLE (850 1575);
FORCEPROP 1 LAST PATH I153
J 0
(850 1625);
DISPLAY 0.978723 (850 1625);
PAINT WHITE (850 1625);
DISPLAY INVISIBLE (850 1625);
FORCEPROP 2 LAST ROOM BMC_VOLT_MONITOR
J 0
(850 1625);
DISPLAY 1.021277 (850 1625);
PAINT ORANGE (850 1625);
DISPLAY INVISIBLE (850 1625);
FORCEADD PVNN_PCH_STBY..1
(800 2025);
FORCEPROP 3 LASTPIN (800 1975) SIG_NAME PVNN_PCH_STBY\g
J 0
(810 1985);
DISPLAY 0.659574 (810 1985);
PAINT MONO (810 1985);
DISPLAY INVISIBLE (810 1985);
FORCEPROP 1 LAST VOLTAGE 1.0V
J 0
(755 1982);
DISPLAY 0.340426 (755 1982);
PAINT SKYBLUE (755 1982);
DISPLAY INVISIBLE (755 1982);
FORCEPROP 2 LAST CDS_LIB mstr_symbols
J 0
(800 2025);
PAINT ORANGE (800 2025);
DISPLAY INVISIBLE (800 2025);
FORCEPROP 1 LAST BODY_TYPE PLUMBING
J 0
(755 1982);
DISPLAY 0.340426 (755 1982);
PAINT GREEN (755 1982);
DISPLAY INVISIBLE (755 1982);
FORCEPROP 1 LAST PATH I154
J 0
(850 2050);
DISPLAY 0.872340 (850 2050);
PAINT AQUA (850 2050);
DISPLAY INVISIBLE (850 2050);
FORCEPROP 1 LAST HDL_POWER PVNN_PCH_STBY
J 1
(800 2075);
DISPLAY 0.872340 (800 2075);
PAINT GREEN (800 2075);
DISPLAY INVISIBLE (800 2075);
FORCEADD FERRITE..4
(800 1850);
FORCEPROP 1 LAST LOCATION FB1U4
J 0
(860 1895);
DISPLAY 0.617021 (860 1895);
PAINT AQUA (860 1895);
FORCEPROP 1 LAST PART_NUMBER 693286-021
J 0
(860 1795);
DISPLAY 0.617021 (860 1795);
PAINT BLUE (860 1795);
FORCEPROP 1 LAST VALUE 30
J 0
(860 1845);
DISPLAY 0.617021 (860 1845);
PAINT SKYBLUE (860 1845);
FORCEPROP 1 LAST PACK_TYPE SMLF
J 0
(860 1745);
DISPLAY 0.617021 (860 1745);
PAINT SKYBLUE (860 1745);
FORCEPROP 1 LAST MATERIAL FB
J 0
(861 1695);
DISPLAY 0.617021 (861 1695);
PAINT SKYBLUE (861 1695);
FORCEPROP 1 LASTPIN (800 1950) $PN 2
J 0
(820 1920);
DISPLAY 0.617021 (820 1920);
PAINT MONO (820 1920);
FORCEPROP 1 LASTPIN (800 1750) $PN 1
J 0
(820 1750);
DISPLAY 0.617021 (820 1750);
PAINT MONO (820 1750);
FORCEPROP 2 LAST CDS_LIB mstr_discrete
J 0
(800 1850);
DISPLAY 1.361702 (800 1850);
PAINT ORANGE (800 1850);
DISPLAY INVISIBLE (800 1850);
FORCEPROP 2 LAST SEC_TYPE SMLF
J 0
(875 2000);
PAINT MONO (875 2000);
DISPLAY INVISIBLE (875 2000);
FORCEPROP 2 LAST BOM_COST SM_HM
J 0
(875 1975);
DISPLAY 1.021277 (875 1975);
PAINT ORANGE (875 1975);
DISPLAY INVISIBLE (875 1975);
FORCEPROP 2 LAST SEC 1
J 0
(875 2000);
DISPLAY 0.936170 (875 2000);
PAINT MONO (875 2000);
DISPLAY INVISIBLE (875 2000);
FORCEPROP 2 LAST CDS_LOCATION FB1U4
J 0
(860 1895);
DISPLAY 0.617021 (860 1895);
PAINT AQUA (860 1895);
DISPLAY INVISIBLE (860 1895);
FORCEPROP 1 LAST PATH I155
J 0
(865 1945);
DISPLAY 0.978723 (865 1945);
PAINT WHITE (865 1945);
DISPLAY INVISIBLE (865 1945);
FORCEPROP 2 LAST ROOM BMC_VOLT_MONITOR
J 0
(875 1925);
DISPLAY 1.021277 (875 1925);
PAINT ORANGE (875 1925);
DISPLAY INVISIBLE (875 1925);
FORCEADD GND..1
(800 1250);
FORCEPROP 3 LASTPIN (800 1300) SIG_NAME GND\g
J 0
(810 1310);
DISPLAY 0.659574 (810 1310);
PAINT MONO (810 1310);
DISPLAY INVISIBLE (810 1310);
FORCEPROP 1 LAST VOLTAGE 0
J 0
(800 1250);
PAINT SKYBLUE (800 1250);
DISPLAY INVISIBLE (800 1250);
FORCEPROP 2 LAST CDS_LIB mstr_symbols
J 0
(800 1250);
DISPLAY 1.361702 (800 1250);
PAINT ORANGE (800 1250);
DISPLAY INVISIBLE (800 1250);
FORCEPROP 1 LAST SIZE 1B
J 0
(875 1200);
DISPLAY 1.148936 (875 1200);
PAINT GREEN (875 1200);
DISPLAY INVISIBLE (875 1200);
FORCEPROP 1 LAST BODY_TYPE PLUMBING
J 0
(755 1207);
DISPLAY 0.340426 (755 1207);
PAINT GREEN (755 1207);
DISPLAY INVISIBLE (755 1207);
FORCEPROP 1 LAST PATH I156
J 0
(875 1250);
DISPLAY 0.872340 (875 1250);
PAINT AQUA (875 1250);
DISPLAY INVISIBLE (875 1250);
FORCEPROP 1 LAST HDL_POWER GND
J 0
(800 1400);
DISPLAY 1.148936 (800 1400);
PAINT GREEN (800 1400);
DISPLAY INVISIBLE (800 1400);
FORCEADD FET_N_DUAL..5
(200 3225);
FORCEPROP 1 LAST LOCATION Q9G1
J 0
(400 3225);
DISPLAY 0.617021 (400 3225);
PAINT AQUA (400 3225);
FORCEPROP 1 LAST PART_NUMBER E40049-001
J 0
(400 3025);
DISPLAY 0.617021 (400 3025);
PAINT BLUE (400 3025);
FORCEPROP 1 LAST VALUE NTJD4001N
J 0
(400 3175);
DISPLAY 0.617021 (400 3175);
PAINT SKYBLUE (400 3175);
FORCEPROP 1 LAST MATERIAL FET
J 0
(400 3125);
DISPLAY 0.617021 (400 3125);
PAINT SKYBLUE (400 3125);
FORCEPROP 1 LASTPIN (200 3025) $PN 4
J 2
(258 3025);
DISPLAY 0.617021 (258 3025);
PAINT WHITE (258 3025);
FORCEPROP 1 LASTPIN (0 3125) $PN 5
J 2
(3 3140);
DISPLAY 0.617021 (3 3140);
PAINT WHITE (3 3140);
FORCEPROP 1 LASTPIN (200 3425) $PN 3
J 2
(253 3390);
DISPLAY 0.617021 (253 3390);
PAINT WHITE (253 3390);
FORCEPROP 1 LAST PACK_TYPE SMLF
J 0
(400 3075);
DISPLAY 0.978723 (400 3075);
PAINT SKYBLUE (400 3075);
DISPLAY INVISIBLE (400 3075);
FORCEPROP 2 LAST SEC_TYPE SMLF
J 0
(400 3325);
DISPLAY 1.021277 (400 3325);
PAINT ORANGE (400 3325);
DISPLAY INVISIBLE (400 3325);
FORCEPROP 0 LAST BOM_COST SM_HM
J 0
(400 3425);
DISPLAY 1.021277 (400 3425);
PAINT ORANGE (400 3425);
DISPLAY INVISIBLE (400 3425);
FORCEPROP 2 LAST CDS_LIB mstr_discrete
J 0
(200 3225);
PAINT ORANGE (200 3225);
DISPLAY INVISIBLE (200 3225);
FORCEPROP 2 LAST SEC 2
J 0
(400 3325);
DISPLAY 0.680851 (400 3325);
PAINT MONO (400 3325);
DISPLAY INVISIBLE (400 3325);
FORCEPROP 2 LAST CDS_LOCATION Q9G1
J 0
(400 3225);
DISPLAY 0.617021 (400 3225);
PAINT AQUA (400 3225);
DISPLAY INVISIBLE (400 3225);
FORCEPROP 1 LAST PATH I157
J 0
(400 3275);
DISPLAY 0.978723 (400 3275);
PAINT BLUE (400 3275);
DISPLAY INVISIBLE (400 3275);
FORCEPROP 0 LAST ROOM BMC_VOLT_MONITOR
J 0
(400 3325);
DISPLAY 1.021277 (400 3325);
PAINT ORANGE (400 3325);
DISPLAY INVISIBLE (400 3325);
FORCEADD GND..1
(-875 2525);
FORCEPROP 3 LASTPIN (-875 2575) SIG_NAME GND\g
J 0
(-865 2585);
DISPLAY 0.659574 (-865 2585);
PAINT MONO (-865 2585);
DISPLAY INVISIBLE (-865 2585);
FORCEPROP 1 LAST VOLTAGE 0
J 0
(-875 2525);
PAINT SKYBLUE (-875 2525);
DISPLAY INVISIBLE (-875 2525);
FORCEPROP 1 LAST SIZE 1B
J 0
(-800 2475);
DISPLAY 1.148936 (-800 2475);
PAINT GREEN (-800 2475);
DISPLAY INVISIBLE (-800 2475);
FORCEPROP 2 LAST CDS_LIB mstr_symbols
J 0
(-875 2525);
PAINT ORANGE (-875 2525);
DISPLAY INVISIBLE (-875 2525);
FORCEPROP 1 LAST BODY_TYPE PLUMBING
J 0
(-920 2482);
DISPLAY 0.340426 (-920 2482);
PAINT GREEN (-920 2482);
DISPLAY INVISIBLE (-920 2482);
FORCEPROP 1 LAST PATH I160
J 0
(-800 2525);
DISPLAY 0.872340 (-800 2525);
PAINT AQUA (-800 2525);
DISPLAY INVISIBLE (-800 2525);
FORCEPROP 1 LAST HDL_POWER GND
J 0
(-875 2675);
DISPLAY 1.148936 (-875 2675);
PAINT GREEN (-875 2675);
DISPLAY INVISIBLE (-875 2675);
FORCEADD OFFPAGE..1
(-2100 2800);
FORCEPROP 2 LAST $XR0 118 
J 0
(-2352 2800);
DISPLAY 0.638298 (-2352 2800);
PAINT MONO (-2352 2800);
FORCEPROP 2 LAST $XR1 145 
J 0
(-2472 2800);
DISPLAY 0.638298 (-2472 2800);
PAINT MONO (-2472 2800);
FORCEPROP 2 LAST CDS_LIB mstr_standard
J 0
(-2100 2800);
PAINT ORANGE (-2100 2800);
DISPLAY INVISIBLE (-2100 2800);
FORCEPROP 1 LAST OFFPAGE TRUE
J 0
(-1775 2675);
DISPLAY 0.872340 (-1775 2675);
PAINT GREEN (-1775 2675);
DISPLAY INVISIBLE (-1775 2675);
FORCEPROP 1 LAST COMMENT_BODY TRUE
J 0
(-1975 2700);
DISPLAY 0.872340 (-1975 2700);
PAINT GREEN (-1975 2700);
DISPLAY INVISIBLE (-1975 2700);
FORCEPROP 2 LAST PATH I161
J 0
(-2350 2850);
DISPLAY 1.021277 (-2350 2850);
PAINT ORANGE (-2350 2850);
DISPLAY INVISIBLE (-2350 2850);
FORCEADD FET_N_DUAL..5
(-875 2900);
FORCEPROP 1 LAST LOCATION Q9G1
J 0
(-675 2900);
DISPLAY 0.617021 (-675 2900);
PAINT AQUA (-675 2900);
FORCEPROP 1 LAST PART_NUMBER E40049-001
J 0
(-675 2700);
DISPLAY 0.617021 (-675 2700);
PAINT BLUE (-675 2700);
FORCEPROP 1 LAST VALUE NTJD4001N
J 0
(-675 2850);
DISPLAY 0.617021 (-675 2850);
PAINT SKYBLUE (-675 2850);
FORCEPROP 1 LAST MATERIAL FET
J 0
(-675 2800);
DISPLAY 0.617021 (-675 2800);
PAINT SKYBLUE (-675 2800);
FORCEPROP 1 LASTPIN (-875 2700) $PN 1
J 2
(-817 2700);
DISPLAY 0.617021 (-817 2700);
PAINT WHITE (-817 2700);
FORCEPROP 1 LASTPIN (-1075 2800) $PN 2
J 2
(-1072 2815);
DISPLAY 0.617021 (-1072 2815);
PAINT WHITE (-1072 2815);
FORCEPROP 1 LASTPIN (-875 3100) $PN 6
J 2
(-822 3065);
DISPLAY 0.617021 (-822 3065);
PAINT WHITE (-822 3065);
FORCEPROP 1 LAST PACK_TYPE SMLF
J 0
(-675 2750);
DISPLAY 0.978723 (-675 2750);
PAINT SKYBLUE (-675 2750);
DISPLAY INVISIBLE (-675 2750);
FORCEPROP 2 LAST CDS_LIB mstr_discrete
J 0
(-875 2900);
PAINT ORANGE (-875 2900);
DISPLAY INVISIBLE (-875 2900);
FORCEPROP 0 LAST BOM_COST SM_HM
J 0
(-675 3100);
DISPLAY 1.021277 (-675 3100);
PAINT ORANGE (-675 3100);
DISPLAY INVISIBLE (-675 3100);
FORCEPROP 2 LAST SEC_TYPE SMLF
J 0
(-675 3000);
DISPLAY 1.021277 (-675 3000);
PAINT ORANGE (-675 3000);
DISPLAY INVISIBLE (-675 3000);
FORCEPROP 2 LAST SEC 1
J 0
(-675 3000);
DISPLAY 0.680851 (-675 3000);
PAINT MONO (-675 3000);
DISPLAY INVISIBLE (-675 3000);
FORCEPROP 2 LAST CDS_LOCATION Q9G1
J 0
(-675 2900);
DISPLAY 0.617021 (-675 2900);
PAINT AQUA (-675 2900);
DISPLAY INVISIBLE (-675 2900);
FORCEPROP 1 LAST PATH I162
J 0
(-675 2950);
DISPLAY 0.978723 (-675 2950);
PAINT BLUE (-675 2950);
DISPLAY INVISIBLE (-675 2950);
FORCEPROP 0 LAST ROOM BMC_VOLT_MONITOR
J 0
(-675 3000);
DISPLAY 1.021277 (-675 3000);
PAINT ORANGE (-675 3000);
DISPLAY INVISIBLE (-675 3000);
FORCEADD RES..2
(-650 3375);
FORCEPROP 1 LAST LOCATION R1U49
J 0
(-605 3500);
DISPLAY 0.617021 (-605 3500);
PAINT AQUA (-605 3500);
FORCEPROP 1 LAST PART_NUMBER G21796-344
J 0
(-610 3250);
DISPLAY 0.617021 (-610 3250);
PAINT BLUE (-610 3250);
FORCEPROP 1 LAST VALUE 2.7K
J 0
(-605 3450);
DISPLAY 0.617021 (-605 3450);
PAINT SKYBLUE (-605 3450);
FORCEPROP 1 LAST TOLERANCE 1%
J 0
(-605 3400);
DISPLAY 0.617021 (-605 3400);
PAINT SKYBLUE (-605 3400);
FORCEPROP 1 LAST PACK_TYPE 0402
J 0
(-610 3200);
DISPLAY 0.617021 (-610 3200);
PAINT SKYBLUE (-610 3200);
FORCEPROP 1 LAST MATERIAL CHIP
J 0
(-610 3300);
DISPLAY 0.617021 (-610 3300);
PAINT SKYBLUE (-610 3300);
FORCEPROP 1 LAST WATTAGE 1/16W
J 0
(-610 3350);
DISPLAY 0.617021 (-610 3350);
PAINT SKYBLUE (-610 3350);
FORCEPROP 1 LASTPIN (-650 3275) $PN 2
J 0
(-645 3285);
DISPLAY 0.617021 (-645 3285);
PAINT ORANGE (-645 3285);
FORCEPROP 1 LASTPIN (-650 3475) $PN 1
J 0
(-645 3437);
DISPLAY 0.617021 (-645 3437);
PAINT ORANGE (-645 3437);
FORCEPROP 2 LAST SEC_TYPE 0402
J 0
(-600 3600);
DISPLAY 1.021277 (-600 3600);
PAINT ORANGE (-600 3600);
DISPLAY INVISIBLE (-600 3600);
FORCEPROP 2 LAST BOM_COST SM_HM
J 0
(-600 3600);
DISPLAY 1.021277 (-600 3600);
PAINT ORANGE (-600 3600);
DISPLAY INVISIBLE (-600 3600);
FORCEPROP 2 LAST CDS_LIB mstr_discrete
J 0
(-650 3375);
PAINT ORANGE (-650 3375);
DISPLAY INVISIBLE (-650 3375);
FORCEPROP 2 LAST SEC 1
J 0
(-600 3600);
DISPLAY 0.680851 (-600 3600);
PAINT MONO (-600 3600);
DISPLAY INVISIBLE (-600 3600);
FORCEPROP 2 LAST CDS_LOCATION R1U49
J 0
(-605 3500);
DISPLAY 0.617021 (-605 3500);
PAINT AQUA (-605 3500);
DISPLAY INVISIBLE (-605 3500);
FORCEPROP 1 LAST PATH I163
J 0
(-600 3550);
DISPLAY 0.978723 (-600 3550);
PAINT WHITE (-600 3550);
DISPLAY INVISIBLE (-600 3550);
FORCEPROP 2 LAST ROOM BMC_VOLT_MONITOR
J 0
(-600 3550);
DISPLAY 1.021277 (-600 3550);
PAINT ORANGE (-600 3550);
DISPLAY INVISIBLE (-600 3550);
FORCEADD RES..2
(-1400 3025);
FORCEPROP 1 LAST LOCATION R9G35
J 0
(-1355 3150);
DISPLAY 0.617021 (-1355 3150);
PAINT AQUA (-1355 3150);
FORCEPROP 1 LAST PART_NUMBER G21796-344
J 0
(-1360 2900);
DISPLAY 0.617021 (-1360 2900);
PAINT BLUE (-1360 2900);
FORCEPROP 1 LAST VALUE 2.7K
J 0
(-1355 3100);
DISPLAY 0.617021 (-1355 3100);
PAINT SKYBLUE (-1355 3100);
FORCEPROP 1 LAST TOLERANCE 1%
J 0
(-1355 3050);
DISPLAY 0.617021 (-1355 3050);
PAINT SKYBLUE (-1355 3050);
FORCEPROP 1 LAST PACK_TYPE 0402
J 0
(-1360 2850);
DISPLAY 0.617021 (-1360 2850);
PAINT SKYBLUE (-1360 2850);
FORCEPROP 1 LAST MATERIAL CHIP
J 0
(-1360 2950);
DISPLAY 0.617021 (-1360 2950);
PAINT SKYBLUE (-1360 2950);
FORCEPROP 1 LAST WATTAGE 1/16W
J 0
(-1360 3000);
DISPLAY 0.617021 (-1360 3000);
PAINT SKYBLUE (-1360 3000);
FORCEPROP 1 LASTPIN (-1400 2925) $PN 2
J 0
(-1395 2935);
DISPLAY 0.617021 (-1395 2935);
PAINT ORANGE (-1395 2935);
FORCEPROP 1 LASTPIN (-1400 3125) $PN 1
J 0
(-1395 3087);
DISPLAY 0.617021 (-1395 3087);
PAINT ORANGE (-1395 3087);
FORCEPROP 2 LAST CDS_LIB mstr_discrete
J 0
(-1400 3025);
PAINT ORANGE (-1400 3025);
DISPLAY INVISIBLE (-1400 3025);
FORCEPROP 2 LAST SEC_TYPE 0402
J 0
(-1350 3250);
DISPLAY 1.021277 (-1350 3250);
PAINT ORANGE (-1350 3250);
DISPLAY INVISIBLE (-1350 3250);
FORCEPROP 2 LAST SEC 1
J 0
(-1350 3250);
DISPLAY 0.680851 (-1350 3250);
PAINT MONO (-1350 3250);
DISPLAY INVISIBLE (-1350 3250);
FORCEPROP 1 LAST PATH I164
J 0
(-1350 3200);
DISPLAY 0.978723 (-1350 3200);
PAINT WHITE (-1350 3200);
DISPLAY INVISIBLE (-1350 3200);
FORCEADD P3V3_STBY..1
(-1400 3325);
FORCEPROP 3 LASTPIN (-1400 3275) SIG_NAME P3V3_STBY\g
J 0
(-1390 3285);
DISPLAY 0.659574 (-1390 3285);
PAINT MONO (-1390 3285);
DISPLAY INVISIBLE (-1390 3285);
FORCEPROP 1 LAST VOLTAGE 3.3V
J 0
(-1445 3282);
DISPLAY 0.340426 (-1445 3282);
PAINT SKYBLUE (-1445 3282);
DISPLAY INVISIBLE (-1445 3282);
FORCEPROP 1 LAST SIZE 1B
J 0
(-1355 3347);
DISPLAY 0.340426 (-1355 3347);
PAINT GREEN (-1355 3347);
DISPLAY INVISIBLE (-1355 3347);
FORCEPROP 2 LAST CDS_LIB mstr_symbols
J 0
(-1400 3325);
PAINT ORANGE (-1400 3325);
DISPLAY INVISIBLE (-1400 3325);
FORCEPROP 1 LAST BODY_TYPE PLUMBING
J 0
(-1445 3282);
DISPLAY 0.340426 (-1445 3282);
PAINT GREEN (-1445 3282);
DISPLAY INVISIBLE (-1445 3282);
FORCEPROP 1 LAST PATH I165
J 0
(-1355 3327);
DISPLAY 0.340426 (-1355 3327);
PAINT GREEN (-1355 3327);
DISPLAY INVISIBLE (-1355 3327);
FORCEPROP 1 LAST HDL_POWER P3V3_STBY
J 0
(-1700 3200);
DISPLAY 0.872340 (-1700 3200);
PAINT ORANGE (-1700 3200);
DISPLAY INVISIBLE (-1700 3200);
FORCEADD P3V3_STBY..1
(-650 3600);
FORCEPROP 3 LASTPIN (-650 3550) SIG_NAME P3V3_STBY\g
J 0
(-640 3560);
DISPLAY 0.659574 (-640 3560);
PAINT MONO (-640 3560);
DISPLAY INVISIBLE (-640 3560);
FORCEPROP 1 LAST VOLTAGE 3.3V
J 0
(-695 3557);
DISPLAY 0.340426 (-695 3557);
PAINT SKYBLUE (-695 3557);
DISPLAY INVISIBLE (-695 3557);
FORCEPROP 1 LAST SIZE 1B
J 0
(-605 3622);
DISPLAY 0.340426 (-605 3622);
PAINT GREEN (-605 3622);
DISPLAY INVISIBLE (-605 3622);
FORCEPROP 2 LAST CDS_LIB mstr_symbols
J 0
(-650 3600);
PAINT ORANGE (-650 3600);
DISPLAY INVISIBLE (-650 3600);
FORCEPROP 1 LAST BODY_TYPE PLUMBING
J 0
(-695 3557);
DISPLAY 0.340426 (-695 3557);
PAINT GREEN (-695 3557);
DISPLAY INVISIBLE (-695 3557);
FORCEPROP 1 LAST PATH I166
J 0
(-605 3602);
DISPLAY 0.340426 (-605 3602);
PAINT GREEN (-605 3602);
DISPLAY INVISIBLE (-605 3602);
FORCEPROP 1 LAST HDL_POWER P3V3_STBY
J 0
(-950 3475);
DISPLAY 0.872340 (-950 3475);
PAINT ORANGE (-950 3475);
DISPLAY INVISIBLE (-950 3475);
FORCEADD OFFPAGE..2
(-4075 3400);
FORCEPROP 2 LAST $XR0 147 
J 0
(-3886 3400);
DISPLAY 0.638298 (-3886 3400);
PAINT MONO (-3886 3400);
FORCEPROP 2 LAST $XR1 165 
J 0
(-3766 3400);
DISPLAY 0.638298 (-3766 3400);
PAINT MONO (-3766 3400);
FORCEPROP 2 LAST CDS_LIB mstr_standard
J 0
(-4075 3400);
DISPLAY 1.361702 (-4075 3400);
PAINT ORANGE (-4075 3400);
DISPLAY INVISIBLE (-4075 3400);
FORCEPROP 1 LAST OFFPAGE TRUE
J 0
(-3750 3275);
PAINT GREEN (-3750 3275);
DISPLAY INVISIBLE (-3750 3275);
FORCEPROP 1 LAST COMMENT_BODY TRUE
J 0
(-4120 3305);
DISPLAY 1.170213 (-4120 3305);
PAINT GREEN (-4120 3305);
DISPLAY INVISIBLE (-4120 3305);
FORCEPROP 2 LAST PATH I55
J 0
(-3875 3450);
PAINT MONO (-3875 3450);
DISPLAY INVISIBLE (-3875 3450);
FORCEADD CAP..1
(-4825 3250);
FORCEPROP 1 LAST LOCATION C1U21
J 0
(-4775 3350);
DISPLAY 0.617021 (-4775 3350);
PAINT AQUA (-4775 3350);
FORCEPROP 1 LAST PART_NUMBER A36095-025
J 0
(-4775 3100);
DISPLAY 0.617021 (-4775 3100);
PAINT BLUE (-4775 3100);
FORCEPROP 1 LAST VALUE 47.0PF
J 0
(-4775 3300);
DISPLAY 0.617021 (-4775 3300);
PAINT SKYBLUE (-4775 3300);
FORCEPROP 1 LAST TOLERANCE 5%
J 0
(-4775 3200);
DISPLAY 0.617021 (-4775 3200);
PAINT SKYBLUE (-4775 3200);
FORCEPROP 1 LAST PACK_TYPE 0402LF
J 0
(-4775 3050);
DISPLAY 0.617021 (-4775 3050);
PAINT SKYBLUE (-4775 3050);
FORCEPROP 1 LAST VOLTAGE 50V
J 0
(-4775 3250);
DISPLAY 0.617021 (-4775 3250);
PAINT SKYBLUE (-4775 3250);
FORCEPROP 1 LAST MATERIAL COG
J 0
(-4775 3150);
DISPLAY 0.617021 (-4775 3150);
PAINT SKYBLUE (-4775 3150);
FORCEPROP 1 LASTPIN (-4825 3150) $PN 2
J 0
(-4815 3130);
DISPLAY 0.617021 (-4815 3130);
PAINT MONO (-4815 3130);
FORCEPROP 1 LASTPIN (-4825 3350) $PN 1
J 0
(-4815 3330);
DISPLAY 0.617021 (-4815 3330);
PAINT MONO (-4815 3330);
FORCEPROP 2 LAST SEC_TYPE 0402LF
J 0
(-4775 3450);
PAINT MONO (-4775 3450);
DISPLAY INVISIBLE (-4775 3450);
FORCEPROP 2 LAST CDS_LIB mstr_discrete
J 0
(-4825 3250);
DISPLAY 1.361702 (-4825 3250);
PAINT ORANGE (-4825 3250);
DISPLAY INVISIBLE (-4825 3250);
FORCEPROP 2 LAST BOM_COST SM_HM
J 0
(-4775 3450);
DISPLAY 1.021277 (-4775 3450);
PAINT ORANGE (-4775 3450);
DISPLAY INVISIBLE (-4775 3450);
FORCEPROP 2 LAST SEC 1
J 0
(-4775 3450);
DISPLAY 0.936170 (-4775 3450);
PAINT MONO (-4775 3450);
DISPLAY INVISIBLE (-4775 3450);
FORCEPROP 2 LAST CDS_LOCATION C1U21
J 0
(-4775 3350);
DISPLAY 0.617021 (-4775 3350);
PAINT AQUA (-4775 3350);
DISPLAY INVISIBLE (-4775 3350);
FORCEPROP 1 LAST PATH I56
J 0
(-4775 3400);
DISPLAY 1.319149 (-4775 3400);
PAINT GREEN (-4775 3400);
DISPLAY INVISIBLE (-4775 3400);
FORCEPROP 2 LAST ROOM BMC_VOLT_MONITOR
J 0
(-4775 3400);
DISPLAY 1.021277 (-4775 3400);
PAINT ORANGE (-4775 3400);
DISPLAY INVISIBLE (-4775 3400);
FORCEADD FERRITE..4
(-4825 3600);
FORCEPROP 1 LAST LOCATION FB1U3
J 0
(-4765 3645);
DISPLAY 0.617021 (-4765 3645);
PAINT AQUA (-4765 3645);
FORCEPROP 1 LAST PART_NUMBER 693286-021
J 0
(-4765 3545);
DISPLAY 0.617021 (-4765 3545);
PAINT BLUE (-4765 3545);
FORCEPROP 1 LAST VALUE 30
J 0
(-4765 3595);
DISPLAY 0.617021 (-4765 3595);
PAINT SKYBLUE (-4765 3595);
FORCEPROP 1 LAST PACK_TYPE SMLF
J 0
(-4765 3495);
DISPLAY 0.617021 (-4765 3495);
PAINT SKYBLUE (-4765 3495);
FORCEPROP 1 LAST MATERIAL FB
J 0
(-4764 3445);
DISPLAY 0.617021 (-4764 3445);
PAINT SKYBLUE (-4764 3445);
FORCEPROP 1 LASTPIN (-4825 3700) $PN 2
J 0
(-4805 3670);
DISPLAY 0.617021 (-4805 3670);
PAINT MONO (-4805 3670);
FORCEPROP 1 LASTPIN (-4825 3500) $PN 1
J 0
(-4805 3500);
DISPLAY 0.617021 (-4805 3500);
PAINT MONO (-4805 3500);
FORCEPROP 2 LAST BOM_COST SM_HM
J 0
(-4750 3725);
DISPLAY 1.021277 (-4750 3725);
PAINT ORANGE (-4750 3725);
DISPLAY INVISIBLE (-4750 3725);
FORCEPROP 2 LAST SEC_TYPE SMLF
J 0
(-4750 3750);
PAINT MONO (-4750 3750);
DISPLAY INVISIBLE (-4750 3750);
FORCEPROP 2 LAST CDS_LIB mstr_discrete
J 0
(-4825 3600);
DISPLAY 1.361702 (-4825 3600);
PAINT ORANGE (-4825 3600);
DISPLAY INVISIBLE (-4825 3600);
FORCEPROP 2 LAST SEC 1
J 0
(-4750 3750);
DISPLAY 0.936170 (-4750 3750);
PAINT MONO (-4750 3750);
DISPLAY INVISIBLE (-4750 3750);
FORCEPROP 2 LAST CDS_LOCATION FB1U3
J 0
(-4765 3645);
DISPLAY 0.617021 (-4765 3645);
PAINT AQUA (-4765 3645);
DISPLAY INVISIBLE (-4765 3645);
FORCEPROP 1 LAST PATH I57
J 0
(-4760 3695);
DISPLAY 1.319149 (-4760 3695);
PAINT GREEN (-4760 3695);
DISPLAY INVISIBLE (-4760 3695);
FORCEPROP 2 LAST ROOM BMC_VOLT_MONITOR
J 0
(-4750 3675);
DISPLAY 1.021277 (-4750 3675);
PAINT ORANGE (-4750 3675);
DISPLAY INVISIBLE (-4750 3675);
FORCEADD GND..1
(-4825 3000);
FORCEPROP 3 LASTPIN (-4825 3050) SIG_NAME GND\g
J 0
(-4815 3060);
DISPLAY 0.659574 (-4815 3060);
PAINT MONO (-4815 3060);
DISPLAY INVISIBLE (-4815 3060);
FORCEPROP 1 LAST VOLTAGE 0
J 0
(-4825 3000);
PAINT SKYBLUE (-4825 3000);
DISPLAY INVISIBLE (-4825 3000);
FORCEPROP 1 LAST SIZE 1B
J 0
(-4750 2950);
DISPLAY 1.148936 (-4750 2950);
PAINT GREEN (-4750 2950);
DISPLAY INVISIBLE (-4750 2950);
FORCEPROP 2 LAST CDS_LIB mstr_symbols
J 0
(-4825 3000);
DISPLAY 1.361702 (-4825 3000);
PAINT ORANGE (-4825 3000);
DISPLAY INVISIBLE (-4825 3000);
FORCEPROP 1 LAST BODY_TYPE PLUMBING
J 0
(-4870 2957);
DISPLAY 0.340426 (-4870 2957);
PAINT GREEN (-4870 2957);
DISPLAY INVISIBLE (-4870 2957);
FORCEPROP 1 LAST PATH I58
J 0
(-4750 3000);
DISPLAY 1.170213 (-4750 3000);
PAINT GREEN (-4750 3000);
DISPLAY INVISIBLE (-4750 3000);
FORCEPROP 1 LAST HDL_POWER GND
J 0
(-4825 3150);
DISPLAY 1.148936 (-4825 3150);
PAINT GREEN (-4825 3150);
DISPLAY INVISIBLE (-4825 3150);
FORCEADD OFFPAGE..2
(-1900 1550);
FORCEPROP 2 LAST $XR0 147 
J 0
(-1711 1550);
DISPLAY 0.638298 (-1711 1550);
PAINT MONO (-1711 1550);
FORCEPROP 2 LAST $XR1 165 
J 0
(-1591 1550);
DISPLAY 0.638298 (-1591 1550);
PAINT MONO (-1591 1550);
FORCEPROP 2 LAST CDS_LIB mstr_standard
J 0
(-1900 1550);
DISPLAY 1.361702 (-1900 1550);
PAINT ORANGE (-1900 1550);
DISPLAY INVISIBLE (-1900 1550);
FORCEPROP 1 LAST OFFPAGE TRUE
J 0
(-1575 1425);
PAINT GREEN (-1575 1425);
DISPLAY INVISIBLE (-1575 1425);
FORCEPROP 1 LAST COMMENT_BODY TRUE
J 0
(-1945 1455);
DISPLAY 1.170213 (-1945 1455);
PAINT GREEN (-1945 1455);
DISPLAY INVISIBLE (-1945 1455);
FORCEPROP 2 LAST PATH I67
J 0
(-1700 1600);
PAINT MONO (-1700 1600);
DISPLAY INVISIBLE (-1700 1600);
FORCEADD CAP..1
(-2500 1350);
FORCEPROP 1 LAST LOCATION C9G21
J 0
(-2450 1450);
DISPLAY 0.617021 (-2450 1450);
PAINT AQUA (-2450 1450);
FORCEPROP 1 LAST PART_NUMBER A36095-025
J 0
(-2450 1200);
DISPLAY 0.617021 (-2450 1200);
PAINT BLUE (-2450 1200);
FORCEPROP 1 LAST VALUE 47.0PF
J 0
(-2450 1400);
DISPLAY 0.617021 (-2450 1400);
PAINT SKYBLUE (-2450 1400);
FORCEPROP 1 LAST TOLERANCE 5%
J 0
(-2450 1300);
DISPLAY 0.617021 (-2450 1300);
PAINT SKYBLUE (-2450 1300);
FORCEPROP 1 LAST PACK_TYPE 0402LF
J 0
(-2450 1150);
DISPLAY 0.617021 (-2450 1150);
PAINT SKYBLUE (-2450 1150);
FORCEPROP 1 LAST VOLTAGE 50V
J 0
(-2450 1350);
DISPLAY 0.617021 (-2450 1350);
PAINT SKYBLUE (-2450 1350);
FORCEPROP 1 LAST MATERIAL COG
J 0
(-2450 1250);
DISPLAY 0.617021 (-2450 1250);
PAINT SKYBLUE (-2450 1250);
FORCEPROP 1 LASTPIN (-2500 1250) $PN 2
J 0
(-2490 1230);
DISPLAY 0.617021 (-2490 1230);
PAINT MONO (-2490 1230);
FORCEPROP 1 LASTPIN (-2500 1450) $PN 1
J 0
(-2490 1430);
DISPLAY 0.617021 (-2490 1430);
PAINT MONO (-2490 1430);
FORCEPROP 2 LAST BOM_COST SM_HM
J 0
(-2450 1550);
DISPLAY 1.021277 (-2450 1550);
PAINT ORANGE (-2450 1550);
DISPLAY INVISIBLE (-2450 1550);
FORCEPROP 2 LAST CDS_LIB mstr_discrete
J 0
(-2500 1350);
DISPLAY 1.361702 (-2500 1350);
PAINT ORANGE (-2500 1350);
DISPLAY INVISIBLE (-2500 1350);
FORCEPROP 2 LAST SEC_TYPE 0402LF
J 0
(-2450 1550);
PAINT MONO (-2450 1550);
DISPLAY INVISIBLE (-2450 1550);
FORCEPROP 2 LAST SEC 1
J 0
(-2450 1550);
DISPLAY 0.936170 (-2450 1550);
PAINT MONO (-2450 1550);
DISPLAY INVISIBLE (-2450 1550);
FORCEPROP 2 LAST CDS_LOCATION C9G21
J 0
(-2450 1450);
DISPLAY 0.617021 (-2450 1450);
PAINT AQUA (-2450 1450);
DISPLAY INVISIBLE (-2450 1450);
FORCEPROP 1 LAST PATH I68
J 0
(-2450 1500);
DISPLAY 1.319149 (-2450 1500);
PAINT GREEN (-2450 1500);
DISPLAY INVISIBLE (-2450 1500);
FORCEPROP 2 LAST ROOM BMC_VOLT_MONITOR
J 0
(-2450 1500);
DISPLAY 1.021277 (-2450 1500);
PAINT ORANGE (-2450 1500);
DISPLAY INVISIBLE (-2450 1500);
FORCEADD GND..1
(-2850 1100);
FORCEPROP 3 LASTPIN (-2850 1150) SIG_NAME GND\g
J 0
(-2840 1160);
DISPLAY 0.659574 (-2840 1160);
PAINT MONO (-2840 1160);
DISPLAY INVISIBLE (-2840 1160);
FORCEPROP 1 LAST VOLTAGE 0
J 0
(-2850 1100);
PAINT SKYBLUE (-2850 1100);
DISPLAY INVISIBLE (-2850 1100);
FORCEPROP 1 LAST SIZE 1B
J 0
(-2775 1050);
DISPLAY 1.148936 (-2775 1050);
PAINT GREEN (-2775 1050);
DISPLAY INVISIBLE (-2775 1050);
FORCEPROP 2 LAST CDS_LIB mstr_symbols
J 0
(-2850 1100);
DISPLAY 1.361702 (-2850 1100);
PAINT ORANGE (-2850 1100);
DISPLAY INVISIBLE (-2850 1100);
FORCEPROP 1 LAST BODY_TYPE PLUMBING
J 0
(-2895 1057);
DISPLAY 0.340426 (-2895 1057);
PAINT GREEN (-2895 1057);
DISPLAY INVISIBLE (-2895 1057);
FORCEPROP 1 LAST PATH I71
J 0
(-2775 1100);
DISPLAY 1.170213 (-2775 1100);
PAINT GREEN (-2775 1100);
DISPLAY INVISIBLE (-2775 1100);
FORCEPROP 1 LAST HDL_POWER GND
J 0
(-2850 1250);
DISPLAY 1.148936 (-2850 1250);
PAINT GREEN (-2850 1250);
DISPLAY INVISIBLE (-2850 1250);
FORCEADD OFFPAGE..2
(-200 1625);
FORCEPROP 2 LAST $XR0 147 
J 0
(-11 1625);
DISPLAY 0.638298 (-11 1625);
PAINT MONO (-11 1625);
FORCEPROP 2 LAST $XR1 165 
J 0
(109 1625);
DISPLAY 0.638298 (109 1625);
PAINT MONO (109 1625);
FORCEPROP 2 LAST CDS_LIB mstr_standard
J 0
(-200 1625);
DISPLAY 1.361702 (-200 1625);
PAINT ORANGE (-200 1625);
DISPLAY INVISIBLE (-200 1625);
FORCEPROP 1 LAST OFFPAGE TRUE
J 0
(125 1500);
PAINT GREEN (125 1500);
DISPLAY INVISIBLE (125 1500);
FORCEPROP 1 LAST COMMENT_BODY TRUE
J 0
(-245 1530);
DISPLAY 1.170213 (-245 1530);
PAINT GREEN (-245 1530);
DISPLAY INVISIBLE (-245 1530);
FORCEPROP 2 LAST PATH I79
J 0
(0 1675);
PAINT MONO (0 1675);
DISPLAY INVISIBLE (0 1675);
FORCEADD CAP..1
(-775 1450);
FORCEPROP 1 LAST LOCATION C9G17
J 0
(-725 1550);
DISPLAY 0.617021 (-725 1550);
PAINT AQUA (-725 1550);
FORCEPROP 1 LAST PART_NUMBER A36095-025
J 0
(-725 1300);
DISPLAY 0.617021 (-725 1300);
PAINT BLUE (-725 1300);
FORCEPROP 1 LAST VALUE 47.0PF
J 0
(-725 1500);
DISPLAY 0.617021 (-725 1500);
PAINT SKYBLUE (-725 1500);
FORCEPROP 1 LAST TOLERANCE 5%
J 0
(-725 1400);
DISPLAY 0.617021 (-725 1400);
PAINT SKYBLUE (-725 1400);
FORCEPROP 1 LAST PACK_TYPE 0402LF
J 0
(-725 1250);
DISPLAY 0.617021 (-725 1250);
PAINT SKYBLUE (-725 1250);
FORCEPROP 1 LAST VOLTAGE 50V
J 0
(-725 1450);
DISPLAY 0.617021 (-725 1450);
PAINT SKYBLUE (-725 1450);
FORCEPROP 1 LAST MATERIAL COG
J 0
(-725 1350);
DISPLAY 0.617021 (-725 1350);
PAINT SKYBLUE (-725 1350);
FORCEPROP 1 LASTPIN (-775 1350) $PN 2
J 0
(-765 1330);
DISPLAY 0.617021 (-765 1330);
PAINT MONO (-765 1330);
FORCEPROP 1 LASTPIN (-775 1550) $PN 1
J 0
(-765 1530);
DISPLAY 0.617021 (-765 1530);
PAINT MONO (-765 1530);
FORCEPROP 2 LAST BOM_COST SM_HM
J 0
(-725 1650);
DISPLAY 1.021277 (-725 1650);
PAINT ORANGE (-725 1650);
DISPLAY INVISIBLE (-725 1650);
FORCEPROP 2 LAST CDS_LIB mstr_discrete
J 0
(-775 1450);
DISPLAY 1.361702 (-775 1450);
PAINT ORANGE (-775 1450);
DISPLAY INVISIBLE (-775 1450);
FORCEPROP 2 LAST SEC_TYPE 0402LF
J 0
(-725 1650);
PAINT MONO (-725 1650);
DISPLAY INVISIBLE (-725 1650);
FORCEPROP 2 LAST SEC 1
J 0
(-725 1650);
DISPLAY 0.936170 (-725 1650);
PAINT MONO (-725 1650);
DISPLAY INVISIBLE (-725 1650);
FORCEPROP 2 LAST CDS_LOCATION C9G17
J 0
(-725 1550);
DISPLAY 0.617021 (-725 1550);
PAINT AQUA (-725 1550);
DISPLAY INVISIBLE (-725 1550);
FORCEPROP 1 LAST PATH I80
J 0
(-725 1600);
DISPLAY 1.319149 (-725 1600);
PAINT GREEN (-725 1600);
DISPLAY INVISIBLE (-725 1600);
FORCEPROP 2 LAST ROOM BMC_VOLT_MONITOR
J 0
(-725 1600);
DISPLAY 1.021277 (-725 1600);
PAINT ORANGE (-725 1600);
DISPLAY INVISIBLE (-725 1600);
FORCEADD RES..2
(-1125 1825);
FORCEPROP 1 LAST LOCATION R1U32
J 0
(-1080 1950);
DISPLAY 0.617021 (-1080 1950);
PAINT AQUA (-1080 1950);
FORCEPROP 1 LAST PART_NUMBER G21796-140
J 0
(-1085 1700);
DISPLAY 0.617021 (-1085 1700);
PAINT BLUE (-1085 1700);
FORCEPROP 1 LAST VALUE 5.11K
J 0
(-1080 1900);
DISPLAY 0.617021 (-1080 1900);
PAINT SKYBLUE (-1080 1900);
FORCEPROP 1 LAST TOLERANCE 1%
J 0
(-1080 1850);
DISPLAY 0.617021 (-1080 1850);
PAINT SKYBLUE (-1080 1850);
FORCEPROP 1 LAST PACK_TYPE 0402
J 0
(-1085 1650);
DISPLAY 0.617021 (-1085 1650);
PAINT SKYBLUE (-1085 1650);
FORCEPROP 1 LAST MATERIAL CHIP
J 0
(-1085 1750);
DISPLAY 0.617021 (-1085 1750);
PAINT SKYBLUE (-1085 1750);
FORCEPROP 1 LAST WATTAGE 1/16W
J 0
(-1085 1800);
DISPLAY 0.617021 (-1085 1800);
PAINT SKYBLUE (-1085 1800);
FORCEPROP 1 LASTPIN (-1125 1725) $PN 2
J 0
(-1120 1735);
DISPLAY 0.617021 (-1120 1735);
PAINT MONO (-1120 1735);
FORCEPROP 1 LASTPIN (-1125 1925) $PN 1
J 0
(-1120 1887);
DISPLAY 0.617021 (-1120 1887);
PAINT MONO (-1120 1887);
FORCEPROP 2 LAST SEC_TYPE 0402
J 0
(-1075 2050);
PAINT MONO (-1075 2050);
DISPLAY INVISIBLE (-1075 2050);
FORCEPROP 2 LAST CDS_LIB mstr_discrete
J 0
(-1125 1825);
DISPLAY 1.361702 (-1125 1825);
PAINT ORANGE (-1125 1825);
DISPLAY INVISIBLE (-1125 1825);
FORCEPROP 2 LAST BOM_COST SM_HM
J 0
(-1075 2050);
DISPLAY 1.021277 (-1075 2050);
PAINT ORANGE (-1075 2050);
DISPLAY INVISIBLE (-1075 2050);
FORCEPROP 2 LAST SEC 1
J 0
(-1075 2050);
DISPLAY 0.936170 (-1075 2050);
PAINT MONO (-1075 2050);
DISPLAY INVISIBLE (-1075 2050);
FORCEPROP 2 LAST CDS_LOCATION R1U32
J 0
(-1080 1950);
DISPLAY 0.617021 (-1080 1950);
PAINT AQUA (-1080 1950);
DISPLAY INVISIBLE (-1080 1950);
FORCEPROP 1 LAST PATH I82
J 0
(-1075 2000);
DISPLAY 1.319149 (-1075 2000);
PAINT GREEN (-1075 2000);
DISPLAY INVISIBLE (-1075 2000);
FORCEPROP 2 LAST ROOM BMC_VOLT_MONITOR
J 0
(-1075 2000);
DISPLAY 1.021277 (-1075 2000);
PAINT ORANGE (-1075 2000);
DISPLAY INVISIBLE (-1075 2000);
FORCEADD RES..2
(-1125 1450);
FORCEPROP 1 LAST LOCATION R1U33
J 0
(-1080 1575);
DISPLAY 0.617021 (-1080 1575);
PAINT AQUA (-1080 1575);
FORCEPROP 1 LAST PART_NUMBER G21796-026
J 0
(-1085 1325);
DISPLAY 0.617021 (-1085 1325);
PAINT BLUE (-1085 1325);
FORCEPROP 1 LAST VALUE 1.00K
J 0
(-1080 1525);
DISPLAY 0.617021 (-1080 1525);
PAINT SKYBLUE (-1080 1525);
FORCEPROP 1 LAST TOLERANCE 1%
J 0
(-1080 1475);
DISPLAY 0.617021 (-1080 1475);
PAINT SKYBLUE (-1080 1475);
FORCEPROP 1 LAST PACK_TYPE 0402
J 0
(-1085 1275);
DISPLAY 0.617021 (-1085 1275);
PAINT SKYBLUE (-1085 1275);
FORCEPROP 1 LAST MATERIAL CHIP
J 0
(-1085 1375);
DISPLAY 0.617021 (-1085 1375);
PAINT SKYBLUE (-1085 1375);
FORCEPROP 1 LAST WATTAGE 1/16W
J 0
(-1085 1425);
DISPLAY 0.617021 (-1085 1425);
PAINT SKYBLUE (-1085 1425);
FORCEPROP 1 LASTPIN (-1125 1350) $PN 2
J 0
(-1120 1360);
DISPLAY 0.617021 (-1120 1360);
PAINT MONO (-1120 1360);
FORCEPROP 1 LASTPIN (-1125 1550) $PN 1
J 0
(-1120 1512);
DISPLAY 0.617021 (-1120 1512);
PAINT MONO (-1120 1512);
FORCEPROP 2 LAST SEC_TYPE 0402
J 0
(-1075 1675);
PAINT MONO (-1075 1675);
DISPLAY INVISIBLE (-1075 1675);
FORCEPROP 2 LAST CDS_LIB mstr_discrete
J 0
(-1125 1450);
DISPLAY 1.361702 (-1125 1450);
PAINT ORANGE (-1125 1450);
DISPLAY INVISIBLE (-1125 1450);
FORCEPROP 2 LAST BOM_COST SM_HM
J 0
(-1075 1675);
DISPLAY 1.021277 (-1075 1675);
PAINT ORANGE (-1075 1675);
DISPLAY INVISIBLE (-1075 1675);
FORCEPROP 2 LAST SEC 1
J 0
(-1075 1675);
DISPLAY 0.936170 (-1075 1675);
PAINT MONO (-1075 1675);
DISPLAY INVISIBLE (-1075 1675);
FORCEPROP 2 LAST CDS_LOCATION R1U33
J 0
(-1080 1575);
DISPLAY 0.617021 (-1080 1575);
PAINT AQUA (-1080 1575);
DISPLAY INVISIBLE (-1080 1575);
FORCEPROP 1 LAST PATH I83
J 0
(-1075 1625);
DISPLAY 1.319149 (-1075 1625);
PAINT GREEN (-1075 1625);
DISPLAY INVISIBLE (-1075 1625);
FORCEPROP 2 LAST ROOM BMC_VOLT_MONITOR
J 0
(-1075 1625);
DISPLAY 1.021277 (-1075 1625);
PAINT ORANGE (-1075 1625);
DISPLAY INVISIBLE (-1075 1625);
FORCEADD GND..1
(-1125 1175);
FORCEPROP 3 LASTPIN (-1125 1225) SIG_NAME GND\g
J 0
(-1115 1235);
DISPLAY 0.659574 (-1115 1235);
PAINT MONO (-1115 1235);
DISPLAY INVISIBLE (-1115 1235);
FORCEPROP 1 LAST VOLTAGE 0
J 0
(-1125 1175);
PAINT SKYBLUE (-1125 1175);
DISPLAY INVISIBLE (-1125 1175);
FORCEPROP 1 LAST SIZE 1B
J 0
(-1050 1125);
DISPLAY 1.148936 (-1050 1125);
PAINT GREEN (-1050 1125);
DISPLAY INVISIBLE (-1050 1125);
FORCEPROP 2 LAST CDS_LIB mstr_symbols
J 0
(-1125 1175);
DISPLAY 1.361702 (-1125 1175);
PAINT ORANGE (-1125 1175);
DISPLAY INVISIBLE (-1125 1175);
FORCEPROP 1 LAST BODY_TYPE PLUMBING
J 0
(-1170 1132);
DISPLAY 0.340426 (-1170 1132);
PAINT GREEN (-1170 1132);
DISPLAY INVISIBLE (-1170 1132);
FORCEPROP 1 LAST PATH I84
J 0
(-1050 1175);
DISPLAY 1.170213 (-1050 1175);
PAINT GREEN (-1050 1175);
DISPLAY INVISIBLE (-1050 1175);
FORCEPROP 1 LAST HDL_POWER GND
J 0
(-1125 1325);
DISPLAY 1.148936 (-1125 1325);
PAINT GREEN (-1125 1325);
DISPLAY INVISIBLE (-1125 1325);
FORCEADD OFFPAGE..2
(-3925 1600);
FORCEPROP 2 LAST $XR0 147 
J 0
(-3736 1600);
DISPLAY 0.638298 (-3736 1600);
PAINT MONO (-3736 1600);
FORCEPROP 2 LAST $XR1 165 
J 0
(-3616 1600);
DISPLAY 0.638298 (-3616 1600);
PAINT MONO (-3616 1600);
FORCEPROP 2 LAST CDS_LIB mstr_standard
J 0
(-3925 1600);
DISPLAY 1.361702 (-3925 1600);
PAINT ORANGE (-3925 1600);
DISPLAY INVISIBLE (-3925 1600);
FORCEPROP 1 LAST OFFPAGE TRUE
J 0
(-3600 1475);
PAINT GREEN (-3600 1475);
DISPLAY INVISIBLE (-3600 1475);
FORCEPROP 1 LAST COMMENT_BODY TRUE
J 0
(-3970 1505);
DISPLAY 1.170213 (-3970 1505);
PAINT GREEN (-3970 1505);
DISPLAY INVISIBLE (-3970 1505);
FORCEPROP 2 LAST PATH I85
J 0
(-3725 1650);
PAINT MONO (-3725 1650);
DISPLAY INVISIBLE (-3725 1650);
FORCEADD CAP..1
(-4525 1425);
FORCEPROP 1 LAST LOCATION C9G20
J 0
(-4475 1525);
DISPLAY 0.617021 (-4475 1525);
PAINT AQUA (-4475 1525);
FORCEPROP 1 LAST PART_NUMBER A36095-025
J 0
(-4475 1275);
DISPLAY 0.617021 (-4475 1275);
PAINT BLUE (-4475 1275);
FORCEPROP 1 LAST VALUE 47.0PF
J 0
(-4475 1475);
DISPLAY 0.617021 (-4475 1475);
PAINT SKYBLUE (-4475 1475);
FORCEPROP 1 LAST TOLERANCE 5%
J 0
(-4475 1375);
DISPLAY 0.617021 (-4475 1375);
PAINT SKYBLUE (-4475 1375);
FORCEPROP 1 LAST PACK_TYPE 0402LF
J 0
(-4475 1225);
DISPLAY 0.617021 (-4475 1225);
PAINT SKYBLUE (-4475 1225);
FORCEPROP 1 LAST VOLTAGE 50V
J 0
(-4475 1425);
DISPLAY 0.617021 (-4475 1425);
PAINT SKYBLUE (-4475 1425);
FORCEPROP 1 LAST MATERIAL COG
J 0
(-4475 1325);
DISPLAY 0.617021 (-4475 1325);
PAINT SKYBLUE (-4475 1325);
FORCEPROP 1 LASTPIN (-4525 1325) $PN 2
J 0
(-4515 1305);
DISPLAY 0.617021 (-4515 1305);
PAINT MONO (-4515 1305);
FORCEPROP 1 LASTPIN (-4525 1525) $PN 1
J 0
(-4515 1505);
DISPLAY 0.617021 (-4515 1505);
PAINT MONO (-4515 1505);
FORCEPROP 2 LAST BOM_COST SM_HM
J 0
(-4475 1625);
DISPLAY 1.021277 (-4475 1625);
PAINT ORANGE (-4475 1625);
DISPLAY INVISIBLE (-4475 1625);
FORCEPROP 2 LAST CDS_LIB mstr_discrete
J 0
(-4525 1425);
DISPLAY 1.361702 (-4525 1425);
PAINT ORANGE (-4525 1425);
DISPLAY INVISIBLE (-4525 1425);
FORCEPROP 2 LAST SEC_TYPE 0402LF
J 0
(-4475 1625);
PAINT MONO (-4475 1625);
DISPLAY INVISIBLE (-4475 1625);
FORCEPROP 2 LAST SEC 1
J 0
(-4475 1625);
DISPLAY 0.936170 (-4475 1625);
PAINT MONO (-4475 1625);
DISPLAY INVISIBLE (-4475 1625);
FORCEPROP 2 LAST CDS_LOCATION C9G20
J 0
(-4475 1525);
DISPLAY 0.617021 (-4475 1525);
PAINT AQUA (-4475 1525);
DISPLAY INVISIBLE (-4475 1525);
FORCEPROP 1 LAST PATH I86
J 0
(-4475 1575);
DISPLAY 1.319149 (-4475 1575);
PAINT GREEN (-4475 1575);
DISPLAY INVISIBLE (-4475 1575);
FORCEPROP 2 LAST ROOM BMC_VOLT_MONITOR
J 0
(-4475 1575);
DISPLAY 1.021277 (-4475 1575);
PAINT ORANGE (-4475 1575);
DISPLAY INVISIBLE (-4475 1575);
FORCEADD RES..2
(-4825 1800);
FORCEPROP 1 LAST LOCATION R1U39
J 0
(-4780 1925);
DISPLAY 0.617021 (-4780 1925);
PAINT AQUA (-4780 1925);
FORCEPROP 1 LAST PART_NUMBER G21796-140
J 0
(-4785 1675);
DISPLAY 0.617021 (-4785 1675);
PAINT BLUE (-4785 1675);
FORCEPROP 1 LAST VALUE 5.11K
J 0
(-4780 1875);
DISPLAY 0.617021 (-4780 1875);
PAINT SKYBLUE (-4780 1875);
FORCEPROP 1 LAST TOLERANCE 1%
J 0
(-4780 1825);
DISPLAY 0.617021 (-4780 1825);
PAINT SKYBLUE (-4780 1825);
FORCEPROP 1 LAST PACK_TYPE 0402
J 0
(-4785 1625);
DISPLAY 0.617021 (-4785 1625);
PAINT SKYBLUE (-4785 1625);
FORCEPROP 1 LAST MATERIAL CHIP
J 0
(-4785 1725);
DISPLAY 0.617021 (-4785 1725);
PAINT SKYBLUE (-4785 1725);
FORCEPROP 1 LAST WATTAGE 1/16W
J 0
(-4785 1775);
DISPLAY 0.617021 (-4785 1775);
PAINT SKYBLUE (-4785 1775);
FORCEPROP 1 LASTPIN (-4825 1700) $PN 2
J 0
(-4820 1710);
DISPLAY 0.617021 (-4820 1710);
PAINT MONO (-4820 1710);
FORCEPROP 1 LASTPIN (-4825 1900) $PN 1
J 0
(-4820 1862);
DISPLAY 0.617021 (-4820 1862);
PAINT MONO (-4820 1862);
FORCEPROP 2 LAST SEC_TYPE 0402
J 0
(-4775 2025);
PAINT MONO (-4775 2025);
DISPLAY INVISIBLE (-4775 2025);
FORCEPROP 2 LAST CDS_LIB mstr_discrete
J 0
(-4825 1800);
DISPLAY 1.361702 (-4825 1800);
PAINT ORANGE (-4825 1800);
DISPLAY INVISIBLE (-4825 1800);
FORCEPROP 2 LAST BOM_COST SM_HM
J 0
(-4775 2025);
DISPLAY 1.021277 (-4775 2025);
PAINT ORANGE (-4775 2025);
DISPLAY INVISIBLE (-4775 2025);
FORCEPROP 2 LAST SEC 1
J 0
(-4775 2025);
DISPLAY 0.936170 (-4775 2025);
PAINT MONO (-4775 2025);
DISPLAY INVISIBLE (-4775 2025);
FORCEPROP 2 LAST CDS_LOCATION R1U39
J 0
(-4780 1925);
DISPLAY 0.617021 (-4780 1925);
PAINT AQUA (-4780 1925);
DISPLAY INVISIBLE (-4780 1925);
FORCEPROP 1 LAST PATH I88
J 0
(-4775 1975);
DISPLAY 1.319149 (-4775 1975);
PAINT GREEN (-4775 1975);
DISPLAY INVISIBLE (-4775 1975);
FORCEPROP 2 LAST ROOM BMC_VOLT_MONITOR
J 0
(-4775 1975);
DISPLAY 1.021277 (-4775 1975);
PAINT ORANGE (-4775 1975);
DISPLAY INVISIBLE (-4775 1975);
FORCEADD GND..1
(-4825 1150);
FORCEPROP 3 LASTPIN (-4825 1200) SIG_NAME GND\g
J 0
(-4815 1210);
DISPLAY 0.659574 (-4815 1210);
PAINT MONO (-4815 1210);
DISPLAY INVISIBLE (-4815 1210);
FORCEPROP 1 LAST VOLTAGE 0
J 0
(-4825 1150);
PAINT SKYBLUE (-4825 1150);
DISPLAY INVISIBLE (-4825 1150);
FORCEPROP 1 LAST SIZE 1B
J 0
(-4750 1100);
DISPLAY 1.148936 (-4750 1100);
PAINT GREEN (-4750 1100);
DISPLAY INVISIBLE (-4750 1100);
FORCEPROP 2 LAST CDS_LIB mstr_symbols
J 0
(-4825 1150);
DISPLAY 1.361702 (-4825 1150);
PAINT ORANGE (-4825 1150);
DISPLAY INVISIBLE (-4825 1150);
FORCEPROP 1 LAST BODY_TYPE PLUMBING
J 0
(-4870 1107);
DISPLAY 0.340426 (-4870 1107);
PAINT GREEN (-4870 1107);
DISPLAY INVISIBLE (-4870 1107);
FORCEPROP 1 LAST PATH I90
J 0
(-4750 1150);
DISPLAY 1.170213 (-4750 1150);
PAINT GREEN (-4750 1150);
DISPLAY INVISIBLE (-4750 1150);
FORCEPROP 1 LAST HDL_POWER GND
J 0
(-4825 1300);
DISPLAY 1.148936 (-4825 1300);
PAINT GREEN (-4825 1300);
DISPLAY INVISIBLE (-4825 1300);
FORCEADD CAD_NOTE..1
(-800 1150);
FORCEPROP 0 LAST L1 AVIN SCALING RESISTORS SHOULD BE PLACED AT THE VOLTAGE RAIL SOURCE
J 0
(-950 1025);
DISPLAY 0.617021 (-950 1025);
PAINT WHITE (-950 1025);
FORCEPROP 0 LAST L2 47PF BYPASS CAP SHOULD BE LOCATED NEAR THE BMC
J 0
(-950 974);
DISPLAY 0.617021 (-950 974);
PAINT WHITE (-950 974);
FORCEPROP 2 LAST CDS_LIB mstr_symbols
J 0
(-800 1150);
PAINT WHITE (-800 1150);
DISPLAY INVISIBLE (-800 1150);
FORCEPROP 1 LAST COMMENT_BODY TRUE
J 0
(-775 1250);
DISPLAY 1.361702 (-775 1250);
PAINT WHITE (-775 1250);
DISPLAY INVISIBLE (-775 1250);
FORCEADD DESIGN_NOTE..1
(700 3775);
FORCEPROP 0 LAST L1 E40049-001 WAS USED INSTEAD OF A C79254-001
J 0
(500 3650);
DISPLAY 1.021277 (500 3650);
PAINT ORANGE (500 3650);
FORCEPROP 0 LAST L2 DUE TO ITS LOWER VGS(TH) THAN THE C79254-001
J 0
(500 3575);
DISPLAY 1.021277 (500 3575);
PAINT ORANGE (500 3575);
FORCEPROP 0 LAST L3 FETS.
J 0
(500 3500);
DISPLAY 1.021277 (500 3500);
PAINT ORANGE (500 3500);
FORCEPROP 2 LAST CDS_LIB mstr_symbols
J 0
(700 3775);
PAINT ORANGE (700 3775);
DISPLAY INVISIBLE (700 3775);
FORCEPROP 1 LAST COMMENT_BODY TRUE
J 0
(725 3875);
DISPLAY 0.978723 (725 3875);
PAINT ORANGE (725 3875);
DISPLAY INVISIBLE (725 3875);
FORCEADD INTEL_CORP_BPAGE..1
(2650 500);
FORCEPROP 1 LAST CDS_CON_LAST_MODIFIED Tue Dec 01 11:52:12 2015
J 0
(1225 825);
PAINT ORANGE (1225 825);
DISPLAY INVISIBLE (1225 825);
FORCEPROP 1 LAST CUSTOM_TXT_CDS <CURRENT_DESIGN_SHEET> OF <TOTAL_DESIGN_SHEETS>
J 0
(2150 525);
PAINT GREEN (2150 525);
FORCEPROP 1 LAST CUSTOM_TXT_CDS <CON_LAST_MODIFIED>
J 0
(725 850);
PAINT GREEN (725 850);
FORCEPROP 2 LAST CUSTOM_TXT_CDS <XR_PAGE_TITLE>
J 0
(-5240 5750);
DISPLAY 0.638298 (-5240 5750);
PAINT PINK (-5240 5750);
DISPLAY INVISIBLE (-5240 5750);
FORCEPROP 1 LAST SCH_ADDRESS3 Santa Clara, CA 95052-8119
J 0
(-1325 525);
DISPLAY 0.617021 (-1325 525);
PAINT GREEN (-1325 525);
FORCEPROP 1 LAST SCH_ADDRESS2 P.O. BOX 58119
J 0
(-1325 575);
DISPLAY 0.617021 (-1325 575);
PAINT GREEN (-1325 575);
FORCEPROP 1 LAST SCH_ADDRESS1 2200 Mission College Blvd.
J 0
(-1325 625);
DISPLAY 0.617021 (-1325 625);
PAINT GREEN (-1325 625);
FORCEPROP 1 LAST SCH_TITLE VOLTAGE MONITORING
J 0
(-5300 550);
DISPLAY 1.212766 (-5300 550);
PAINT ORANGE (-5300 550);
FORCEPROP 1 LAST SCH_NUMBER H4694802
J 0
(1350 650);
DISPLAY 1.212766 (1350 650);
PAINT YELLOW (1350 650);
FORCEPROP 1 LAST SCH_DEPT BESD
J 1
(-1800 600);
DISPLAY 1.212766 (-1800 600);
PAINT YELLOW (-1800 600);
FORCEPROP 1 LAST SCH_REV 2.420
J 0
(2400 650);
DISPLAY 0.978723 (2400 650);
PAINT YELLOW (2400 650);
FORCEPROP 2 LAST CDS_LIB mstr_symbols
J 0
(2650 500);
PAINT MONO (2650 500);
DISPLAY INVISIBLE (2650 500);
FORCEPROP 2 LAST PAGE_BORDER TRUE
J 0
(-5240 5750);
DISPLAY 0.851064 (-5240 5750);
PAINT PINK (-5240 5750);
DISPLAY INVISIBLE (-5240 5750);
FORCEPROP 1 LAST COMMENT_BODY TRUE
J 0
(2662 512);
DISPLAY 0.468085 (2662 512);
PAINT GREEN (2662 512);
DISPLAY INVISIBLE (2662 512);
FORCEPROP 2 LAST CDS_XR_PAGE_TITLE CR-169 : @BASEBOARD_FAB2_LIB.BASEBOARD_FAB2(SCH_1):PAGE169
J 0
(-5240 5750);
DISPLAY 0.638298 (-5240 5750);
PAINT PINK (-5240 5750);
DISPLAY INVISIBLE (-5240 5750);
WIRE 16 -1 (400 2550)(400 2625);
WIRE 16 -1 (800 2550)(800 2600);
WIRE 16 -1 (-2850 1850)(-2850 1925);
WIRE 16 -1 (-4825 3725)(-4825 3700);
FORCEPROP 0 LAST CDS_PHYS_NET_NAME <<OCC_ONLY>>
J 1
(-4825 3750);
PAINT ORANGE (-4825 3750);
DISPLAY INVISIBLE (-4825 3750);
WIRE 16 -1 (-4825 1950)(-4825 1900);
WIRE 16 -1 (-1125 1975)(-1125 1925);
WIRE 16 -1 (-4350 4450)(-4350 4375);
WIRE 16 -1 (-4350 4375)(-4700 4375);
WIRE 16 -1 (-4700 4450)(-4700 4375);
WIRE 16 -1 (-4700 4350)(-4700 4375);
WIRE 16 -1 (-4700 5050)(-4700 5125);
WIRE 16 -1 (-2550 4500)(-2550 4425);
WIRE 16 -1 (-2550 4425)(-2875 4425);
WIRE 16 -1 (-2875 4525)(-2875 4425);
WIRE 16 -1 (-2875 4400)(-2875 4425);
WIRE 16 -1 (-2875 5150)(-2875 5100);
WIRE 16 -1 (800 1975)(800 1950);
FORCEPROP 0 LAST CDS_PHYS_NET_NAME <<OCC_ONLY>>
J 1
(800 2000);
PAINT ORANGE (800 2000);
DISPLAY INVISIBLE (800 2000);
WIRE 16 -1 (800 1375)(800 1300);
WIRE 16 -1 (-875 2700)(-875 2575);
WIRE 16 -1 (-1400 3125)(-1400 3275);
WIRE 16 -1 (-650 3475)(-650 3550);
WIRE 16 -1 (-4825 3050)(-4825 3150);
WIRE 16 -1 (-2500 1250)(-2500 1175);
WIRE 16 -1 (-2500 1175)(-2850 1175);
WIRE 16 -1 (-2850 1250)(-2850 1175);
WIRE 16 -1 (-2850 1150)(-2850 1175);
WIRE 16 -1 (-775 1350)(-775 1250);
WIRE 16 -1 (-775 1250)(-1125 1250);
WIRE 16 -1 (-1125 1350)(-1125 1250);
WIRE 16 -1 (-1125 1225)(-1125 1250);
WIRE 16 -1 (-4525 1325)(-4525 1225);
WIRE 16 -1 (-4525 1225)(-4825 1225);
WIRE 16 -1 (-4825 1325)(-4825 1225);
WIRE 16 -1 (-4825 1200)(-4825 1225);
WIRE 16 -1 (-4525 1525)(-4525 1600);
WIRE 16 -1 (-3975 1600)(-4525 1600);
FORCEPROP 0 LAST CDS_PHYS_NET_NAME <<OCC_ONLY>>
J 1
(-4475 1650);
PAINT ORANGE (-4475 1650);
DISPLAY INVISIBLE (-4475 1650);
FORCEPROP 0 LAST VOLTAGE +1.8V
J 0
(-4450 1675);
DISPLAY 1.021277 (-4450 1675);
PAINT SKYBLUE (-4450 1675);
DISPLAY INVISIBLE (-4450 1675);
FORCEPROP 2 LAST SIG_NAME A_P3V3_STBY_SCALED
J 0
(-4450 1610);
DISPLAY 0.617021 (-4450 1610);
PAINT ORANGE (-4450 1610);
WIRE 16 -1 (-4825 1600)(-4525 1600);
WIRE 16 -1 (-4825 1600)(-4825 1700);
WIRE 16 -1 (-4825 1525)(-4825 1600);
WIRE 16 -1 (-4125 3400)(-4825 3400);
FORCEPROP 0 LAST CDS_PHYS_NET_NAME <<OCC_ONLY>>
J 1
(-4450 3450);
PAINT ORANGE (-4450 3450);
DISPLAY INVISIBLE (-4450 3450);
FORCEPROP 0 LAST VOLTAGE +1.2V
J 0
(-4200 3475);
DISPLAY 1.021277 (-4200 3475);
PAINT SKYBLUE (-4200 3475);
DISPLAY INVISIBLE (-4200 3475);
FORCEPROP 2 LAST SIG_NAME A_P1V05_STBY_PCH_SENSOR
J 0
(-4675 3410);
DISPLAY 0.617021 (-4675 3410);
PAINT ORANGE (-4675 3410);
WIRE 16 -1 (-4825 3400)(-4825 3500);
WIRE 16 -1 (-4825 3350)(-4825 3400);
WIRE 16 -1 (-4350 4650)(-4350 4750);
WIRE 16 -1 (-4000 4750)(-4350 4750);
FORCEPROP 2 LAST SIG_NAME A_P5V_SCALED
J 0
(-4325 4760);
DISPLAY 0.617021 (-4325 4760);
PAINT ORANGE (-4325 4760);
WIRE 16 -1 (-4700 4750)(-4350 4750);
FORCEPROP 0 LAST VOLTAGE +2V
J 0
(-4450 4800);
DISPLAY 1.021277 (-4450 4800);
PAINT SKYBLUE (-4450 4800);
DISPLAY INVISIBLE (-4450 4800);
WIRE 16 -1 (-4700 4850)(-4700 4750);
WIRE 16 -1 (-4700 4650)(-4700 4750);
WIRE 16 -1 (-2500 1450)(-2500 1550);
WIRE 16 -1 (-1950 1550)(-2500 1550);
FORCEPROP 0 LAST CDS_PHYS_NET_NAME <<OCC_ONLY>>
J 1
(-2475 1600);
PAINT ORANGE (-2475 1600);
DISPLAY INVISIBLE (-2475 1600);
FORCEPROP 0 LAST VOLTAGE +2V
J 0
(-2475 1650);
DISPLAY 1.021277 (-2475 1650);
PAINT SKYBLUE (-2475 1650);
DISPLAY INVISIBLE (-2475 1650);
FORCEPROP 2 LAST SIG_NAME A_P5V_STBY_SCALED
J 0
(-2350 1560);
DISPLAY 0.617021 (-2350 1560);
PAINT ORANGE (-2350 1560);
WIRE 16 -1 (-2850 1550)(-2500 1550);
WIRE 16 -1 (-2850 1650)(-2850 1550);
WIRE 16 -1 (-2850 1450)(-2850 1550);
WIRE 16 -1 (-775 1550)(-775 1625);
WIRE 16 -1 (-250 1625)(-775 1625);
FORCEPROP 0 LAST CDS_PHYS_NET_NAME <<OCC_ONLY>>
J 1
(-350 1675);
PAINT ORANGE (-350 1675);
DISPLAY INVISIBLE (-350 1675);
FORCEPROP 0 LAST VOLTAGE +2V
J 0
(-350 1725);
DISPLAY 1.021277 (-350 1725);
PAINT SKYBLUE (-350 1725);
DISPLAY INVISIBLE (-350 1725);
FORCEPROP 2 LAST SIG_NAME A_P12V_STBY_SCALED
J 0
(-725 1635);
DISPLAY 0.617021 (-725 1635);
PAINT ORANGE (-725 1635);
WIRE 16 -1 (-1125 1625)(-775 1625);
WIRE 16 -1 (-1125 1625)(-1125 1725);
WIRE 16 -1 (-1125 1550)(-1125 1625);
WIRE 16 -1 (-1400 2925)(-1400 2800);
WIRE 16 -1 (-1400 2800)(-1075 2800);
WIRE 16 -1 (-2050 2800)(-1400 2800);
FORCEPROP 0 LAST SIG_NAME FM_BATTERY_SENSE_EN_N
J 0
(-2035 2810);
DISPLAY 0.617021 (-2035 2810);
PAINT ORANGE (-2035 2810);
WIRE 16 -1 (-650 3275)(-650 3125);
WIRE 16 -1 (-650 3125)(0 3125);
FORCEPROP 0 LAST SIG_NAME FM_BATTERY_SENSE_EN
J 0
(-510 3135);
DISPLAY 0.617021 (-510 3135);
PAINT ORANGE (-510 3135);
FORCEPROP 2 LASTPROP $XRERR UNIQUE?
J 0
(-750 3135);
DISPLAY 0.638298 (-750 3135);
PAINT MONO (-750 3135);
DISPLAY INVISIBLE (-750 3135);
WIRE 16 -1 (-875 3125)(-650 3125);
WIRE 16 -1 (-875 3100)(-875 3125);
WIRE 16 -1 (-2550 4700)(-2550 4800);
WIRE 16 -1 (-2100 4800)(-2550 4800);
FORCEPROP 0 LAST VOLTAGE +2V
J 0
(-2475 4875);
DISPLAY 1.021277 (-2475 4875);
PAINT SKYBLUE (-2475 4875);
DISPLAY INVISIBLE (-2475 4875);
FORCEPROP 2 LAST SIG_NAME A_P3V3_SCALED
J 0
(-2475 4810);
DISPLAY 0.617021 (-2475 4810);
PAINT ORANGE (-2475 4810);
WIRE 16 -1 (-2875 4800)(-2550 4800);
WIRE 16 -1 (-2875 4800)(-2875 4900);
WIRE 16 -1 (-2875 4725)(-2875 4800);
WIRE 16 -1 (1600 1650)(800 1650);
FORCEPROP 0 LAST CDS_PHYS_NET_NAME <<OCC_ONLY>>
J 1
(1175 1700);
PAINT ORANGE (1175 1700);
DISPLAY INVISIBLE (1175 1700);
FORCEPROP 0 LAST VOLTAGE +1.2V
J 0
(1425 1725);
DISPLAY 1.021277 (1425 1725);
PAINT SKYBLUE (1425 1725);
DISPLAY INVISIBLE (1425 1725);
FORCEPROP 2 LAST SIG_NAME A_PVNN_STBY_PCH_SENSOR
J 0
(1000 1660);
DISPLAY 0.617021 (1000 1660);
PAINT ORANGE (1000 1660);
WIRE 16 -1 (800 1650)(800 1750);
WIRE 16 -1 (800 1575)(800 1650);
WIRE 16 -1 (800 2800)(800 2900);
WIRE 16 -1 (1175 2900)(800 2900);
FORCEPROP 0 LAST CDS_PHYS_NET_NAME <<OCC_ONLY>>
J 1
(975 2950);
PAINT ORANGE (975 2950);
DISPLAY INVISIBLE (975 2950);
FORCEPROP 0 LAST VOLTAGE +1V
J 0
(975 3000);
DISPLAY 1.021277 (975 3000);
PAINT SKYBLUE (975 3000);
DISPLAY INVISIBLE (975 3000);
WIRE 16 -1 (800 2900)(400 2900);
FORCEPROP 2 LAST SIG_NAME A_P3V_BAT_SCALED
J 0
(665 2910);
DISPLAY 0.617021 (665 2910);
PAINT ORANGE (665 2910);
WIRE 16 -1 (400 2825)(400 2900);
WIRE 16 -1 (200 2900)(400 2900);
WIRE 16 -1 (200 2900)(200 3025);
WIRE 16 -1 (200 3925)(200 3425);
FORCEPROP 0 LAST VOLTAGE +3V
J 0
(200 3450);
DISPLAY 1.021277 (200 3450);
PAINT SKYBLUE (200 3450);
DISPLAY INVISIBLE (200 3450);
FORCEPROP 0 LAST SIG_NAME P3V_BAT_SOURCE_R
R 1
J 0
(190 3385);
DISPLAY 0.617021 (190 3385);
PAINT ORANGE (190 3385);
FORCEPROP 2 LASTPROP $XRERR UNIQUE?
J 0
(-50 3385);
DISPLAY 0.638298 (-50 3385);
PAINT MONO (-50 3385);
DISPLAY INVISIBLE (-50 3385);
WIRE 16 -1 (200 4125)(200 4225);
WIRE 16 -1 (-350 4225)(200 4225);
FORCEPROP 2 LAST SIG_NAME A_P3V_BAT_R
J 0
(-360 4235);
DISPLAY 0.617021 (-360 4235);
PAINT ORANGE (-360 4235);
DOT 1 (-2875 4425);
DOT 1 (-2875 4800);
DOT 1 (-2550 4800);
DOT 1 (800 2900);
DOT 1 (400 2900);
DOT 1 (-650 3125);
DOT 1 (-1400 2800);
DOT 1 (-2850 1175);
DOT 1 (-2850 1550);
DOT 1 (-2500 1550);
DOT 1 (-4825 1225);
DOT 1 (-4525 1600);
DOT 1 (-4825 1600);
DOT 1 (-1125 1250);
DOT 1 (-1125 1625);
DOT 1 (-775 1625);
DOT 1 (800 1650);
DOT 1 (-4700 4750);
DOT 1 (-4700 4375);
DOT 1 (-4825 3400);
DOT 1 (-4350 4750);
FORCENOTE
ROOM=SM_HM
(-5144 797) 0;
DISPLAY LEFT (-5144 797);
DISPLAY 0.617021 (-5144 797);
PAINT PURPLE (-5144 797);
QUIT
